G04 ================== begin FILE IDENTIFICATION RECORD ==================*
G04 Layout Name:  15126-1b.brd*
G04 Film Name:    BMASK*
G04 File Format:  Gerber RS274X*
G04 File Origin:  Cadence Allegro 16.6-2015-S079*
G04 Origin Date:  Fri Feb 10 17:21:49 2017*
G04 *
G04 Layer:  VIA CLASS/SOLDERMASK_BOTTOM*
G04 Layer:  PIN/SOLDERMASK_BOTTOM*
G04 Layer:  PACKAGE GEOMETRY/SOLDERMASK_BOTTOM*
G04 Layer:  DRAWING FORMAT/LAYER_SOLDER_B*
G04 Layer:  BOARD GEOMETRY/SOLDERMASK_BOTTOM*
G04 Layer:  DRAWING FORMAT/LAYER_PCB_STORY*
G04 *
G04 Offset:    (0.00 0.00)*
G04 Mirror:    No*
G04 Mode:      Positive*
G04 Rotation:  0*
G04 FullContactRelief:  No*
G04 UndefLineWidth:     6.00*
G04 ================== end FILE IDENTIFICATION RECORD ====================*
%FSLAX35Y35*MOIN*%
%IR0*IPPOS*OFA0.00000B0.00000*MIA0B0*SFA1.00000B1.00000*%
%AMMACRO129*
4,1,40,.011,.007,
.011,-.007,
.010939,-.007695,
.010759,-.008368,
.010464,-.009,
.010064,-.009571,
.009571,-.010064,
.009,-.010464,
.008368,-.010759,
.007695,-.010939,
.007,-.011,
-.007,-.011,
-.007695,-.010939,
-.008368,-.010759,
-.009,-.010464,
-.009571,-.010064,
-.010064,-.009571,
-.010464,-.009,
-.010759,-.008368,
-.010939,-.007695,
-.011,-.007,
-.011,.007,
-.010939,.007695,
-.010759,.008368,
-.010464,.009,
-.010064,.009571,
-.009571,.010064,
-.009,.010464,
-.008368,.010759,
-.007695,.010939,
-.007,.011,
.007,.011,
.007695,.010939,
.008368,.010759,
.009,.010464,
.009571,.010064,
.010064,.009571,
.010464,.009,
.010759,.008368,
.010939,.007695,
.011,.007,
0.0*
%
%ADD129MACRO129*%
%AMMACRO161*
4,1,40,-.017,-.013,
-.017,.013,
-.016939,.013695,
-.016759,.014368,
-.016464,.015,
-.016064,.015571,
-.015571,.016064,
-.015,.016464,
-.014368,.016759,
-.013695,.016939,
-.013,.017,
.013,.017,
.013695,.016939,
.014368,.016759,
.015,.016464,
.015571,.016064,
.016064,.015571,
.016464,.015,
.016759,.014368,
.016939,.013695,
.017,.013,
.017,-.013,
.016939,-.013695,
.016759,-.014368,
.016464,-.015,
.016064,-.015571,
.015571,-.016064,
.015,-.016464,
.014368,-.016759,
.013695,-.016939,
.013,-.017,
-.013,-.017,
-.013695,-.016939,
-.014368,-.016759,
-.015,-.016464,
-.015571,-.016064,
-.016064,-.015571,
-.016464,-.015,
-.016759,-.014368,
-.016939,-.013695,
-.017,-.013,
0.0*
%
%ADD161MACRO161*%
%AMMACRO157*
4,1,40,.013,-.017,
-.013,-.017,
-.013695,-.016939,
-.014368,-.016759,
-.015,-.016464,
-.015571,-.016064,
-.016064,-.015571,
-.016464,-.015,
-.016759,-.014368,
-.016939,-.013695,
-.017,-.013,
-.017,.013,
-.016939,.013695,
-.016759,.014368,
-.016464,.015,
-.016064,.015571,
-.015571,.016064,
-.015,.016464,
-.014368,.016759,
-.013695,.016939,
-.013,.017,
.013,.017,
.013695,.016939,
.014368,.016759,
.015,.016464,
.015571,.016064,
.016064,.015571,
.016464,.015,
.016759,.014368,
.016939,.013695,
.017,.013,
.017,-.013,
.016939,-.013695,
.016759,-.014368,
.016464,-.015,
.016064,-.015571,
.015571,-.016064,
.015,-.016464,
.014368,-.016759,
.013695,-.016939,
.013,-.017,
0.0*
%
%ADD157MACRO157*%
%AMMACRO146*
4,1,40,.0105,.015,
-.0105,.015,
-.011195,.014939,
-.011868,.014759,
-.0125,.014464,
-.013071,.014064,
-.013564,.013571,
-.013964,.013,
-.014259,.012368,
-.014439,.011695,
-.0145,.011,
-.0145,-.011,
-.014439,-.011695,
-.014259,-.012368,
-.013964,-.013,
-.013564,-.013571,
-.013071,-.014064,
-.0125,-.014464,
-.011868,-.014759,
-.011195,-.014939,
-.0105,-.015,
.0105,-.015,
.011195,-.014939,
.011868,-.014759,
.0125,-.014464,
.013071,-.014064,
.013564,-.013571,
.013964,-.013,
.014259,-.012368,
.014439,-.011695,
.0145,-.011,
.0145,.011,
.014439,.011695,
.014259,.012368,
.013964,.013,
.013564,.013571,
.013071,.014064,
.0125,.014464,
.011868,.014759,
.011195,.014939,
.0105,.015,
0.0*
%
%ADD146MACRO146*%
%AMMACRO98*
21,1,.02,.007,0.0,0.0,11.*%
%ADD98MACRO98*%
%AMMACRO99*
21,1,.02,.007,0.0,0.0,12.*%
%ADD99MACRO99*%
%ADD79O,.062X.111*%
%AMMACRO56*
4,1,8,.0825,.065,
.0825,-.065,
-.0175,-.065,
-.0175,-.087,
-.0825,-.087,
-.0825,.087,
-.0175,.087,
-.0175,.065,
.0825,.065,
0.0*
%
%ADD56MACRO56*%
%AMMACRO147*
21,1,.02,.007,0.0,0.0,16.*%
%ADD147MACRO147*%
%AMMACRO136*
21,1,.007,.02,0.0,0.0,11.32*%
%ADD136MACRO136*%
%AMMACRO96*
21,1,.02,.007,0.0,0.0,11.5*%
%ADD96MACRO96*%
%AMMACRO137*
21,1,.02,.007,0.0,0.0,22.5*%
%ADD137MACRO137*%
%ADD78R,.02X.007*%
%ADD67R,.007X.02*%
%AMMACRO57*
21,1,.02,.007,0.0,0.0,45.*%
%ADD57MACRO57*%
%ADD93R,.007X.02*%
%ADD52R,.02X.007*%
%AMMACRO39*
4,1,12,-.0195,-.0325,
-.0195,.0325,
.0195,.0325,
.0195,.0195,
-.0005,.0195,
-.0005,.0065,
.0195,.0065,
.0195,-.0065,
-.0005,-.0065,
-.0005,-.0195,
.0195,-.0195,
.0195,-.0325,
-.0195,-.0325,
0.0*
%
%ADD39MACRO39*%
%ADD36R,.134X.024*%
%ADD12R,.053X.106*%
%ADD23C,.02*%
%ADD213C,.03*%
%ADD218R,.008X.014*%
%ADD176C,.04*%
%ADD166C,.031*%
%ADD203R,.014X.008*%
%ADD119C,.05*%
%ADD100C,.014*%
%ADD14C,.032*%
%ADD35R,.134X.047*%
%ADD21C,.06*%
%ADD16C,.024*%
%ADD197C,.052*%
%ADD102C,.016*%
%ADD13C,.034*%
%ADD182C,.062*%
%ADD33C,.044*%
%ADD22C,.08*%
%ADD18C,.026*%
%ADD15C,.071*%
%ADD144C,.063*%
%ADD135C,.054*%
%ADD53C,.045*%
%ADD34C,.036*%
%ADD199C,.055*%
%ADD164C,.037*%
%ADD125C,.064*%
%ADD80C,.019*%
%ADD38C,.046*%
%ADD183C,.047*%
%ADD178R,.031X.031*%
%ADD141C,.056*%
%ADD97C,.065*%
%AMMACRO87*
21,1,.02,.007,0.0,0.0,78.302*%
%ADD87MACRO87*%
%AMMACRO72*
4,1,8,-.0585,-.0725,
-.0585,.0725,
.0585,.0725,
.0585,.04275,
.0185,.04275,
.0185,-.04275,
.0585,-.04275,
.0585,-.0725,
-.0585,-.0725,
0.0*
%
%ADD72MACRO72*%
%ADD37C,.074*%
%AMMACRO92*
21,1,.02,.007,0.0,0.0,79.032*%
%ADD92MACRO92*%
%ADD49C,.039*%
%ADD45C,.057*%
%ADD30C,.084*%
%ADD20R,.06X.06*%
%AMMACRO127*
21,1,.02,.007,0.0,0.0,.657*%
%ADD127MACRO127*%
%ADD19C,.086*%
%ADD174C,.069*%
%AMMACRO113*
21,1,.02,.007,0.0,0.0,88.125*%
%ADD113MACRO113*%
%ADD201R,.045X.045*%
%ADD167R,.054X.054*%
%AMMACRO111*
21,1,.02,.007,0.0,0.0,88.522*%
%ADD111MACRO111*%
%AMMACRO108*
21,1,.02,.007,0.0,0.0,76.651*%
%ADD108MACRO108*%
%AMMACRO103*
21,1,.02,.007,0.0,0.0,50.659*%
%ADD103MACRO103*%
%AMMACRO101*
21,1,.02,.007,0.0,0.0,75.526*%
%ADD101MACRO101*%
%ADD223R,.055X.055*%
%ADD138R,.037X.037*%
%ADD126R,.064X.064*%
%ADD207R,.047X.047*%
%AMMACRO173*
21,1,.02,.007,0.0,0.0,90.657*%
%ADD173MACRO173*%
%AMMACRO172*
21,1,.02,.007,0.0,0.0,45.657*%
%ADD172MACRO172*%
%AMMACRO112*
21,1,.02,.007,0.0,0.0,88.245*%
%ADD112MACRO112*%
%AMMACRO180*
4,1,40,-.011,-.007,
-.011,.007,
-.010939,.007695,
-.010759,.008368,
-.010464,.009,
-.010064,.009571,
-.009571,.010064,
-.009,.010464,
-.008368,.010759,
-.007695,.010939,
-.007,.011,
.007,.011,
.007695,.010939,
.008368,.010759,
.009,.010464,
.009571,.010064,
.010064,.009571,
.010464,.009,
.010759,.008368,
.010939,.007695,
.011,.007,
.011,-.007,
.010939,-.007695,
.010759,-.008368,
.010464,-.009,
.010064,-.009571,
.009571,-.010064,
.009,-.010464,
.008368,-.010759,
.007695,-.010939,
.007,-.011,
-.007,-.011,
-.007695,-.010939,
-.008368,-.010759,
-.009,-.010464,
-.009571,-.010064,
-.010064,-.009571,
-.010464,-.009,
-.010759,-.008368,
-.010939,-.007695,
-.011,-.007,
0.0*
%
%ADD180MACRO180*%
%AMMACRO115*
21,1,.02,.007,0.0,0.0,87.823*%
%ADD115MACRO115*%
%AMMACRO65*
4,1,40,.007,-.011,
-.007,-.011,
-.007695,-.010939,
-.008368,-.010759,
-.009,-.010464,
-.009571,-.010064,
-.010064,-.009571,
-.010464,-.009,
-.010759,-.008368,
-.010939,-.007695,
-.011,-.007,
-.011,.007,
-.010939,.007695,
-.010759,.008368,
-.010464,.009,
-.010064,.009571,
-.009571,.010064,
-.009,.010464,
-.008368,.010759,
-.007695,.010939,
-.007,.011,
.007,.011,
.007695,.010939,
.008368,.010759,
.009,.010464,
.009571,.010064,
.010064,.009571,
.010464,.009,
.010759,.008368,
.010939,.007695,
.011,.007,
.011,-.007,
.010939,-.007695,
.010759,-.008368,
.010464,-.009,
.010064,-.009571,
.009571,-.010064,
.009,-.010464,
.008368,-.010759,
.007695,-.010939,
.007,-.011,
0.0*
%
%ADD65MACRO65*%
%ADD50R,.039X.039*%
%AMMACRO114*
21,1,.02,.007,0.0,0.0,88.67*%
%ADD114MACRO114*%
%AMMACRO88*
21,1,.02,.007,0.0,0.0,78.329*%
%ADD88MACRO88*%
%AMMACRO86*
21,1,.02,.007,0.0,0.0,78.77*%
%ADD86MACRO86*%
%AMMACRO109*
21,1,.02,.007,0.0,0.0,88.86*%
%ADD109MACRO109*%
%AMMACRO107*
21,1,.02,.007,0.0,0.0,88.474*%
%ADD107MACRO107*%
%AMMACRO116*
21,1,.02,.007,0.0,0.0,88.493*%
%ADD116MACRO116*%
%AMMACRO27*
4,1,40,-.012,-.008,
-.012,.008,
-.011939,.008695,
-.011759,.009368,
-.011464,.01,
-.011064,.010571,
-.010571,.011064,
-.01,.011464,
-.009368,.011759,
-.008695,.011939,
-.008,.012,
.008,.012,
.008695,.011939,
.009368,.011759,
.01,.011464,
.010571,.011064,
.011064,.010571,
.011464,.01,
.011759,.009368,
.011939,.008695,
.012,.008,
.012,-.008,
.011939,-.008695,
.011759,-.009368,
.011464,-.01,
.011064,-.010571,
.010571,-.011064,
.01,-.011464,
.009368,-.011759,
.008695,-.011939,
.008,-.012,
-.008,-.012,
-.008695,-.011939,
-.009368,-.011759,
-.01,-.011464,
-.010571,-.011064,
-.011064,-.010571,
-.011464,-.01,
-.011759,-.009368,
-.011939,-.008695,
-.012,-.008,
0.0*
%
%ADD27MACRO27*%
%AMMACRO132*
4,1,8,.0034,.0082,
-.0034,.0082,
-.0082,.0034,
-.0082,-.00341,
-.00341,-.0082,
.0034,-.0082,
.0082,-.0034,
.0082,.0034,
.0034,.0082,
0.0*
%
%ADD132MACRO132*%
%AMMACRO68*
4,1,40,-.008,.012,
.008,.012,
.008695,.011939,
.009368,.011759,
.01,.011464,
.010571,.011064,
.011064,.010571,
.011464,.01,
.011759,.009368,
.011939,.008695,
.012,.008,
.012,-.008,
.011939,-.008695,
.011759,-.009368,
.011464,-.01,
.011064,-.010571,
.010571,-.011064,
.01,-.011464,
.009368,-.011759,
.008695,-.011939,
.008,-.012,
-.008,-.012,
-.008695,-.011939,
-.009368,-.011759,
-.01,-.011464,
-.010571,-.011064,
-.011064,-.010571,
-.011464,-.01,
-.011759,-.009368,
-.011939,-.008695,
-.012,-.008,
-.012,.008,
-.011939,.008695,
-.011759,.009368,
-.011464,.01,
-.011064,.010571,
-.010571,.011064,
-.01,.011464,
-.009368,.011759,
-.008695,.011939,
-.008,.012,
0.0*
%
%ADD68MACRO68*%
%AMMACRO154*
4,1,40,-.013,.017,
.013,.017,
.013695,.016939,
.014368,.016759,
.015,.016464,
.015571,.016064,
.016064,.015571,
.016464,.015,
.016759,.014368,
.016939,.013695,
.017,.013,
.017,-.013,
.016939,-.013695,
.016759,-.014368,
.016464,-.015,
.016064,-.015571,
.015571,-.016064,
.015,-.016464,
.014368,-.016759,
.013695,-.016939,
.013,-.017,
-.013,-.017,
-.013695,-.016939,
-.014368,-.016759,
-.015,-.016464,
-.015571,-.016064,
-.016064,-.015571,
-.016464,-.015,
-.016759,-.014368,
-.016939,-.013695,
-.017,-.013,
-.017,.013,
-.016939,.013695,
-.016759,.014368,
-.016464,.015,
-.016064,.015571,
-.015571,.016064,
-.015,.016464,
-.014368,.016759,
-.013695,.016939,
-.013,.017,
0.0*
%
%ADD154MACRO154*%
%AMMACRO134*
4,1,8,.0082,-.0034,
.0082,.0034,
.0034,.0082,
-.00341,.0082,
-.0082,.00341,
-.0082,-.0034,
-.0034,-.0082,
.0034,-.0082,
.0082,-.0034,
0.0*
%
%ADD134MACRO134*%
%AMMACRO158*
4,1,40,.017,.013,
.017,-.013,
.016939,-.013695,
.016759,-.014368,
.016464,-.015,
.016064,-.015571,
.015571,-.016064,
.015,-.016464,
.014368,-.016759,
.013695,-.016939,
.013,-.017,
-.013,-.017,
-.013695,-.016939,
-.014368,-.016759,
-.015,-.016464,
-.015571,-.016064,
-.016064,-.015571,
-.016464,-.015,
-.016759,-.014368,
-.016939,-.013695,
-.017,-.013,
-.017,.013,
-.016939,.013695,
-.016759,.014368,
-.016464,.015,
-.016064,.015571,
-.015571,.016064,
-.015,.016464,
-.014368,.016759,
-.013695,.016939,
-.013,.017,
.013,.017,
.013695,.016939,
.014368,.016759,
.015,.016464,
.015571,.016064,
.016064,.015571,
.016464,.015,
.016759,.014368,
.016939,.013695,
.017,.013,
0.0*
%
%ADD158MACRO158*%
%AMMACRO110*
21,1,.02,.007,0.0,0.0,88.889*%
%ADD110MACRO110*%
%AMMACRO181*
4,1,40,-.011,-.007,
-.011,.007,
-.010939,.007695,
-.010759,.008368,
-.010464,.009,
-.010064,.009571,
-.009571,.010064,
-.009,.010464,
-.008368,.010759,
-.007695,.010939,
-.007,.011,
.007,.011,
.007695,.010939,
.008368,.010759,
.009,.010464,
.009571,.010064,
.010064,.009571,
.010464,.009,
.010759,.008368,
.010939,.007695,
.011,.007,
.011,-.007,
.010939,-.007695,
.010759,-.008368,
.010464,-.009,
.010064,-.009571,
.009571,-.010064,
.009,-.010464,
.008368,-.010759,
.007695,-.010939,
.007,-.011,
-.007,-.011,
-.007695,-.010939,
-.008368,-.010759,
-.009,-.010464,
-.009571,-.010064,
-.010064,-.009571,
-.010464,-.009,
-.010759,-.008368,
-.010939,-.007695,
-.011,-.007,
0.0*
%
%ADD181MACRO181*%
%AMMACRO66*
4,1,40,.007,-.011,
-.007,-.011,
-.007695,-.010939,
-.008368,-.010759,
-.009,-.010464,
-.009571,-.010064,
-.010064,-.009571,
-.010464,-.009,
-.010759,-.008368,
-.010939,-.007695,
-.011,-.007,
-.011,.007,
-.010939,.007695,
-.010759,.008368,
-.010464,.009,
-.010064,.009571,
-.009571,.010064,
-.009,.010464,
-.008368,.010759,
-.007695,.010939,
-.007,.011,
.007,.011,
.007695,.010939,
.008368,.010759,
.009,.010464,
.009571,.010064,
.010064,.009571,
.010464,.009,
.010759,.008368,
.010939,.007695,
.011,.007,
.011,-.007,
.010939,-.007695,
.010759,-.008368,
.010464,-.009,
.010064,-.009571,
.009571,-.010064,
.009,-.010464,
.008368,-.010759,
.007695,-.010939,
.007,-.011,
0.0*
%
%ADD66MACRO66*%
%AMMACRO145*
4,1,40,-.0105,-.015,
.0105,-.015,
.011195,-.014939,
.011868,-.014759,
.0125,-.014464,
.013071,-.014064,
.013564,-.013571,
.013964,-.013,
.014259,-.012368,
.014439,-.011695,
.0145,-.011,
.0145,.011,
.014439,.011695,
.014259,.012368,
.013964,.013,
.013564,.013571,
.013071,.014064,
.0125,.014464,
.011868,.014759,
.011195,.014939,
.0105,.015,
-.0105,.015,
-.011195,.014939,
-.011868,.014759,
-.0125,.014464,
-.013071,.014064,
-.013564,.013571,
-.013964,.013,
-.014259,.012368,
-.014439,.011695,
-.0145,.011,
-.0145,-.011,
-.014439,-.011695,
-.014259,-.012368,
-.013964,-.013,
-.013564,-.013571,
-.013071,-.014064,
-.0125,-.014464,
-.011868,-.014759,
-.011195,-.014939,
-.0105,-.015,
0.0*
%
%ADD145MACRO145*%
%ADD26R,.12X.1*%
%ADD48R,.1X.12*%
%AMMACRO28*
4,1,40,-.012,-.008,
-.012,.008,
-.011939,.008695,
-.011759,.009368,
-.011464,.01,
-.011064,.010571,
-.010571,.011064,
-.01,.011464,
-.009368,.011759,
-.008695,.011939,
-.008,.012,
.008,.012,
.008695,.011939,
.009368,.011759,
.01,.011464,
.010571,.011064,
.011064,.010571,
.011464,.01,
.011759,.009368,
.011939,.008695,
.012,.008,
.012,-.008,
.011939,-.008695,
.011759,-.009368,
.011464,-.01,
.011064,-.010571,
.010571,-.011064,
.01,-.011464,
.009368,-.011759,
.008695,-.011939,
.008,-.012,
-.008,-.012,
-.008695,-.011939,
-.009368,-.011759,
-.01,-.011464,
-.010571,-.011064,
-.011064,-.010571,
-.011464,-.01,
-.011759,-.009368,
-.011939,-.008695,
-.012,-.008,
0.0*
%
%ADD28MACRO28*%
%AMMACRO69*
4,1,40,-.008,.012,
.008,.012,
.008695,.011939,
.009368,.011759,
.01,.011464,
.010571,.011064,
.011064,.010571,
.011464,.01,
.011759,.009368,
.011939,.008695,
.012,.008,
.012,-.008,
.011939,-.008695,
.011759,-.009368,
.011464,-.01,
.011064,-.010571,
.010571,-.011064,
.01,-.011464,
.009368,-.011759,
.008695,-.011939,
.008,-.012,
-.008,-.012,
-.008695,-.011939,
-.009368,-.011759,
-.01,-.011464,
-.010571,-.011064,
-.011064,-.010571,
-.011464,-.01,
-.011759,-.009368,
-.011939,-.008695,
-.012,-.008,
-.012,.008,
-.011939,.008695,
-.011759,.009368,
-.011464,.01,
-.011064,.010571,
-.010571,.011064,
-.01,.011464,
-.009368,.011759,
-.008695,.011939,
-.008,.012,
0.0*
%
%ADD69MACRO69*%
%AMMACRO155*
4,1,40,-.013,.017,
.013,.017,
.013695,.016939,
.014368,.016759,
.015,.016464,
.015571,.016064,
.016064,.015571,
.016464,.015,
.016759,.014368,
.016939,.013695,
.017,.013,
.017,-.013,
.016939,-.013695,
.016759,-.014368,
.016464,-.015,
.016064,-.015571,
.015571,-.016064,
.015,-.016464,
.014368,-.016759,
.013695,-.016939,
.013,-.017,
-.013,-.017,
-.013695,-.016939,
-.014368,-.016759,
-.015,-.016464,
-.015571,-.016064,
-.016064,-.015571,
-.016464,-.015,
-.016759,-.014368,
-.016939,-.013695,
-.017,-.013,
-.017,.013,
-.016939,.013695,
-.016759,.014368,
-.016464,.015,
-.016064,.015571,
-.015571,.016064,
-.015,.016464,
-.014368,.016759,
-.013695,.016939,
-.013,.017,
0.0*
%
%ADD155MACRO155*%
%ADD25R,.02X.02*%
%AMMACRO159*
4,1,40,.017,.013,
.017,-.013,
.016939,-.013695,
.016759,-.014368,
.016464,-.015,
.016064,-.015571,
.015571,-.016064,
.015,-.016464,
.014368,-.016759,
.013695,-.016939,
.013,-.017,
-.013,-.017,
-.013695,-.016939,
-.014368,-.016759,
-.015,-.016464,
-.015571,-.016064,
-.016064,-.015571,
-.016464,-.015,
-.016759,-.014368,
-.016939,-.013695,
-.017,-.013,
-.017,.013,
-.016939,.013695,
-.016759,.014368,
-.016464,.015,
-.016064,.015571,
-.015571,.016064,
-.015,.016464,
-.014368,.016759,
-.013695,.016939,
-.013,.017,
.013,.017,
.013695,.016939,
.014368,.016759,
.015,.016464,
.015571,.016064,
.016064,.015571,
.016464,.015,
.016759,.014368,
.016939,.013695,
.017,.013,
0.0*
%
%ADD159MACRO159*%
%ADD17R,.02X.02*%
%ADD212O,.041X.06*%
%ADD210R,.06X.01*%
%ADD205R,.05X.02*%
%ADD216R,.022X.04*%
%AMMACRO187*
4,1,21,.015,.006,
-.009,.006,
-.010042,.005909,
-.011052,.005638,
-.012,.005196,
-.012857,.004596,
-.013596,.003857,
-.014196,.003,
-.014638,.002052,
-.014909,.001042,
-.015,0.0,
-.014909,-.001042,
-.014638,-.002052,
-.014196,-.003,
-.013596,-.003857,
-.012857,-.004596,
-.012,-.005196,
-.011052,-.005638,
-.010042,-.005909,
-.009,-.006,
.015,-.006,
.015,.006,
0.0*
%
%ADD187MACRO187*%
%ADD177R,.102X.145*%
%AMMACRO58*
21,1,.02,.007,0.0,0.0,135.*%
%ADD58MACRO58*%
%ADD24R,.04X.05*%
%AMMACRO193*
4,1,21,.006,-.015,
.006,.009,
.005909,.010042,
.005638,.011052,
.005196,.012,
.004596,.012857,
.003857,.013596,
.003,.014196,
.002052,.014638,
.001042,.014909,
0.0,.015,
-.001042,.014909,
-.002052,.014638,
-.003,.014196,
-.003857,.013596,
-.004596,.012857,
-.005196,.012,
-.005638,.011052,
-.005909,.010042,
-.006,.009,
-.006,-.015,
.006,-.015,
0.0*
%
%ADD193MACRO193*%
%ADD189R,.014X.04*%
%ADD142R,.06X.03*%
%ADD73R,.02X.071*%
%ADD70R,.05X.04*%
%ADD63R,.015X.04*%
%ADD41R,.04X.06*%
%ADD198R,.012X.026*%
%AMMACRO171*
21,1,.02,.007,0.0,0.0,135.11*%
%ADD171MACRO171*%
%ADD151R,.06X.014*%
%AMMACRO140*
21,1,.02,.007,0.0,0.0,164.*%
%ADD140MACRO140*%
%ADD118R,.04X.015*%
%AMMACRO90*
21,1,.02,.007,0.0,0.0,101.243*%
%ADD90MACRO90*%
%AMMACRO89*
21,1,.02,.007,0.0,0.0,101.144*%
%ADD89MACRO89*%
%ADD61R,.012X.035*%
%ADD60R,.04X.016*%
%ADD59R,.035X.03*%
%ADD51R,.02X.045*%
%AMMACRO217*
4,1,48,.0225,.036,
.026668,.035635,
.030708,.034553,
.0345,.032785,
.037927,.030385,
.040885,.027427,
.043285,.024,
.045053,.020208,
.046135,.016168,
.0465,.012,
.046135,.007832,
.045053,.003792,
.043285,0.0,
.040885,-.003427,
.037927,-.006385,
.0345,-.008785,
.030708,-.010553,
.026668,-.011635,
.0225,-.012,
.0015,-.012,
.001135,-.016168,
.000053,-.020208,
-.001715,-.024,
-.004115,-.027427,
-.007073,-.030385,
-.0105,-.032785,
-.014292,-.034553,
-.018332,-.035635,
-.0225,-.036,
-.026668,-.035635,
-.030708,-.034553,
-.0345,-.032785,
-.037927,-.030385,
-.040885,-.027427,
-.043285,-.024,
-.045053,-.020208,
-.046135,-.016168,
-.0465,-.012,
-.0465,.012,
-.046135,.016168,
-.045053,.020208,
-.043285,.024,
-.040885,.027427,
-.037927,.030385,
-.0345,.032785,
-.030708,.034553,
-.026668,.035635,
-.0225,.036,
.0225,.036,
0.0*
%
%ADD217MACRO217*%
%ADD192R,.02X.055*%
%ADD184O,.032X.036*%
%ADD175O,.126X.191*%
%ADD165C,.102*%
%ADD153R,.04X.016*%
%ADD149R,.016X.04*%
%ADD143R,.014X.06*%
%AMMACRO94*
21,1,.02,.007,0.0,0.0,160.5*%
%ADD94MACRO94*%
%ADD74C,.12*%
%ADD64R,.045X.02*%
%ADD54R,.03X.035*%
%ADD47C,.111*%
%ADD42R,.026X.012*%
%ADD191O,.191X.126*%
%AMMACRO85*
21,1,.02,.007,0.0,0.0,166.*%
%ADD85MACRO85*%
%ADD62R,.012X.037*%
%ADD200O,.07X.046*%
%ADD55R,.065X.02*%
%ADD31C,.14*%
%AMMACRO104*
21,1,.02,.007,0.0,0.0,159.*%
%ADD104MACRO104*%
%ADD75C,.15*%
%ADD44R,.018X.05*%
%ADD202R,.018X.07*%
%AMMACRO124*
21,1,.02,.007,0.0,0.0,146.5*%
%ADD124MACRO124*%
%ADD219R,.016X.037*%
%ADD117R,.07X.018*%
%ADD40R,.039X.013*%
%ADD211R,.014X.048*%
%ADD204R,.037X.016*%
%ADD150R,.065X.025*%
%AMMACRO95*
21,1,.02,.007,0.0,0.0,148.5*%
%ADD95MACRO95*%
%AMMACRO188*
4,1,21,-.006,.015,
-.006,-.009,
-.005909,-.010042,
-.005638,-.011052,
-.005196,-.012,
-.004596,-.012857,
-.003857,-.013596,
-.003,-.014196,
-.002052,-.014638,
-.001042,-.014909,
0.0,-.015,
.001042,-.014909,
.002052,-.014638,
.003,-.014196,
.003857,-.013596,
.004596,-.012857,
.005196,-.012,
.005638,-.011052,
.005909,-.010042,
.006,-.009,
.006,.015,
-.006,.015,
0.0*
%
%ADD188MACRO188*%
%ADD179R,.048X.016*%
%AMMACRO84*
21,1,.02,.007,0.0,0.0,167.5*%
%ADD84MACRO84*%
%ADD11R,.045X.055*%
%ADD224R,.039X.035*%
%AMMACRO220*
21,1,.02,.007,0.0,0.0,166.601*%
%ADD220MACRO220*%
%ADD215R,.038X.063*%
%ADD209R,.025X.076*%
%AMMACRO195*
4,1,21,.015,.006,
-.009,.006,
-.010042,.005909,
-.011052,.005638,
-.012,.005196,
-.012857,.004596,
-.013596,.003857,
-.014196,.003,
-.014638,.002052,
-.014909,.001042,
-.015,0.0,
-.014909,-.001042,
-.014638,-.002052,
-.014196,-.003,
-.013596,-.003857,
-.012857,-.004596,
-.012,-.005196,
-.011052,-.005638,
-.010042,-.005909,
-.009,-.006,
.015,-.006,
.015,.006,
0.0*
%
%ADD195MACRO195*%
%ADD130R,.085X.015*%
%AMMACRO91*
21,1,.02,.007,0.0,0.0,100.577*%
%ADD91MACRO91*%
%AMMACRO82*
21,1,.02,.007,0.0,0.0,168.5*%
%ADD82MACRO82*%
%ADD29R,.055X.045*%
%ADD190R,.076X.025*%
%AMMACRO139*
21,1,.02,.007,0.0,0.0,169.5*%
%ADD139MACRO139*%
%AMMACRO120*
4,1,21,-.01,.004,
-.010695,.003939,
-.011368,.003759,
-.012,.003464,
-.012571,.003064,
-.013064,.002571,
-.013464,.002,
-.013759,.001368,
-.013939,.000695,
-.014,0.0,
-.013939,-.000695,
-.013759,-.001368,
-.013464,-.002,
-.013064,-.002571,
-.012571,-.003064,
-.012,-.003464,
-.011368,-.003759,
-.010695,-.003939,
-.01,-.004,
.014,-.004,
.014,.004,
-.01,.004,
0.0*
%
%ADD120MACRO120*%
%AMMACRO81*
21,1,.02,.007,0.0,0.0,145.821*%
%ADD81MACRO81*%
%ADD77R,.035X.039*%
%ADD32R,.14X.14*%
%ADD225O,.094X.048*%
%ADD10C,.238*%
%AMMACRO168*
21,1,.02,.007,0.0,0.0,134.753*%
%ADD168MACRO168*%
%ADD206O,.098X.046*%
%ADD163R,.059X.036*%
%ADD162C,.276*%
%AMMACRO186*
4,1,21,.006,-.015,
.006,.009,
.005909,.010042,
.005638,.011052,
.005196,.012,
.004596,.012857,
.003857,.013596,
.003,.014196,
.002052,.014638,
.001042,.014909,
0.0,.015,
-.001042,.014909,
-.002052,.014638,
-.003,.014196,
-.003857,.013596,
-.004596,.012857,
-.005196,.012,
-.005638,.011052,
-.005909,.010042,
-.006,.009,
-.006,-.015,
.006,-.015,
0.0*
%
%ADD186MACRO186*%
%AMMACRO76*
4,1,8,.0585,.0725,
.0585,-.0725,
-.0585,-.0725,
-.0585,-.04275,
-.0185,-.04275,
-.0185,.04275,
-.0585,.04275,
-.0585,.0725,
.0585,.0725,
0.0*
%
%ADD76MACRO76*%
%AMMACRO194*
4,1,21,-.015,-.006,
.009,-.006,
.010042,-.005909,
.011052,-.005638,
.012,-.005196,
.012857,-.004596,
.013596,-.003857,
.014196,-.003,
.014638,-.002052,
.014909,-.001042,
.015,0.0,
.014909,.001042,
.014638,.002052,
.014196,.003,
.013596,.003857,
.012857,.004596,
.012,.005196,
.011052,.005638,
.010042,.005909,
.009,.006,
-.015,.006,
-.015,-.006,
0.0*
%
%ADD194MACRO194*%
%ADD208O,.099X.048*%
%AMMACRO185*
4,1,21,-.015,-.006,
.009,-.006,
.010042,-.005909,
.011052,-.005638,
.012,-.005196,
.012857,-.004596,
.013596,-.003857,
.014196,-.003,
.014638,-.002052,
.014909,-.001042,
.015,0.0,
.014909,.001042,
.014638,.002052,
.014196,.003,
.013596,.003857,
.012857,.004596,
.012,.005196,
.011052,.005638,
.010042,.005909,
.009,.006,
-.015,.006,
-.015,-.006,
0.0*
%
%ADD185MACRO185*%
%AMMACRO170*
21,1,.02,.007,0.0,0.0,135.657*%
%ADD170MACRO170*%
%AMMACRO196*
4,1,21,-.006,.015,
-.006,-.009,
-.005909,-.010042,
-.005638,-.011052,
-.005196,-.012,
-.004596,-.012857,
-.003857,-.013596,
-.003,-.014196,
-.002052,-.014638,
-.001042,-.014909,
0.0,-.015,
.001042,-.014909,
.002052,-.014638,
.003,-.014196,
.003857,-.013596,
.004596,-.012857,
.005196,-.012,
.005638,-.011052,
.005909,-.010042,
.006,-.009,
.006,.015,
-.006,.015,
0.0*
%
%ADD196MACRO196*%
%AMMACRO148*
4,1,40,.024,-.012,
.024,.012,
.023878,.013389,
.023518,.014736,
.022928,.016,
.022128,.017142,
.021142,.018128,
.02,.018928,
.018736,.019518,
.017389,.019878,
.016,.02,
-.016,.02,
-.017389,.019878,
-.018736,.019518,
-.02,.018928,
-.021142,.018128,
-.022128,.017142,
-.022928,.016,
-.023518,.014736,
-.023878,.013389,
-.024,.012,
-.024,-.012,
-.023878,-.013389,
-.023518,-.014736,
-.022928,-.016,
-.022128,-.017142,
-.021142,-.018128,
-.02,-.018928,
-.018736,-.019518,
-.017389,-.019878,
-.016,-.02,
.016,-.02,
.017389,-.019878,
.018736,-.019518,
.02,-.018928,
.021142,-.018128,
.022128,-.017142,
.022928,-.016,
.023518,-.014736,
.023878,-.013389,
.024,-.012,
0.0*
%
%ADD148MACRO148*%
%AMMACRO123*
4,1,21,-.004,-.01,
-.003939,-.010695,
-.003759,-.011368,
-.003464,-.012,
-.003064,-.012571,
-.002571,-.013064,
-.002,-.013464,
-.001368,-.013759,
-.000695,-.013939,
0.0,-.014,
.000695,-.013939,
.001368,-.013759,
.002,-.013464,
.002571,-.013064,
.003064,-.012571,
.003464,-.012,
.003759,-.011368,
.003939,-.010695,
.004,-.01,
.004,.014,
-.004,.014,
-.004,-.01,
0.0*
%
%ADD123MACRO123*%
%AMMACRO83*
21,1,.02,.007,0.0,0.0,168.917*%
%ADD83MACRO83*%
%AMMACRO221*
4,1,40,.008,-.012,
-.008,-.012,
-.008695,-.011939,
-.009368,-.011759,
-.01,-.011464,
-.010571,-.011064,
-.011064,-.010571,
-.011464,-.01,
-.011759,-.009368,
-.011939,-.008695,
-.012,-.008,
-.012,.008,
-.011939,.008695,
-.011759,.009368,
-.011464,.01,
-.011064,.010571,
-.010571,.011064,
-.01,.011464,
-.009368,.011759,
-.008695,.011939,
-.008,.012,
.008,.012,
.008695,.011939,
.009368,.011759,
.01,.011464,
.010571,.011064,
.011064,.010571,
.011464,.01,
.011759,.009368,
.011939,.008695,
.012,.008,
.012,-.008,
.011939,-.008695,
.011759,-.009368,
.011464,-.01,
.011064,-.010571,
.010571,-.011064,
.01,-.011464,
.009368,-.011759,
.008695,-.011939,
.008,-.012,
0.0*
%
%ADD221MACRO221*%
%AMMACRO106*
4,1,40,.012,.008,
.012,-.008,
.011939,-.008695,
.011759,-.009368,
.011464,-.01,
.011064,-.010571,
.010571,-.011064,
.01,-.011464,
.009368,-.011759,
.008695,-.011939,
.008,-.012,
-.008,-.012,
-.008695,-.011939,
-.009368,-.011759,
-.01,-.011464,
-.010571,-.011064,
-.011064,-.010571,
-.011464,-.01,
-.011759,-.009368,
-.011939,-.008695,
-.012,-.008,
-.012,.008,
-.011939,.008695,
-.011759,.009368,
-.011464,.01,
-.011064,.010571,
-.010571,.011064,
-.01,.011464,
-.009368,.011759,
-.008695,.011939,
-.008,.012,
.008,.012,
.008695,.011939,
.009368,.011759,
.01,.011464,
.010571,.011064,
.011064,.010571,
.011464,.01,
.011759,.009368,
.011939,.008695,
.012,.008,
0.0*
%
%ADD106MACRO106*%
%AMMACRO71*
4,1,40,-.007,.011,
.007,.011,
.007695,.010939,
.008368,.010759,
.009,.010464,
.009571,.010064,
.010064,.009571,
.010464,.009,
.010759,.008368,
.010939,.007695,
.011,.007,
.011,-.007,
.010939,-.007695,
.010759,-.008368,
.010464,-.009,
.010064,-.009571,
.009571,-.010064,
.009,-.010464,
.008368,-.010759,
.007695,-.010939,
.007,-.011,
-.007,-.011,
-.007695,-.010939,
-.008368,-.010759,
-.009,-.010464,
-.009571,-.010064,
-.010064,-.009571,
-.010464,-.009,
-.010759,-.008368,
-.010939,-.007695,
-.011,-.007,
-.011,.007,
-.010939,.007695,
-.010759,.008368,
-.010464,.009,
-.010064,.009571,
-.009571,.010064,
-.009,.010464,
-.008368,.010759,
-.007695,.010939,
-.007,.011,
0.0*
%
%ADD71MACRO71*%
%AMMACRO169*
21,1,.02,.007,0.0,0.0,179.539*%
%ADD169MACRO169*%
%AMMACRO152*
4,1,8,-.0082,-.00339,
-.00339,-.0082,
.00339,-.0082,
.00821,-.00339,
.00821,.00339,
.00339,.0082,
-.00339,.0082,
-.0082,.00339,
-.0082,-.00339,
0.0*
%
%ADD152MACRO152*%
%AMMACRO133*
4,1,8,-.0082,.0034,
-.0082,-.0034,
-.0034,-.0082,
.00341,-.0082,
.0082,-.00341,
.0082,.0034,
.0034,.0082,
-.0034,.0082,
-.0082,.0034,
0.0*
%
%ADD133MACRO133*%
%AMMACRO131*
4,1,8,-.0034,-.0082,
.0034,-.0082,
.0082,-.0034,
.0082,.00341,
.00341,.0082,
-.0034,.0082,
-.0082,.0034,
-.0082,-.0034,
-.0034,-.0082,
0.0*
%
%ADD131MACRO131*%
%AMMACRO128*
4,1,40,.011,.007,
.011,-.007,
.010939,-.007695,
.010759,-.008368,
.010464,-.009,
.010064,-.009571,
.009571,-.010064,
.009,-.010464,
.008368,-.010759,
.007695,-.010939,
.007,-.011,
-.007,-.011,
-.007695,-.010939,
-.008368,-.010759,
-.009,-.010464,
-.009571,-.010064,
-.010064,-.009571,
-.010464,-.009,
-.010759,-.008368,
-.010939,-.007695,
-.011,-.007,
-.011,.007,
-.010939,.007695,
-.010759,.008368,
-.010464,.009,
-.010064,.009571,
-.009571,.010064,
-.009,.010464,
-.008368,.010759,
-.007695,.010939,
-.007,.011,
.007,.011,
.007695,.010939,
.008368,.010759,
.009,.010464,
.009571,.010064,
.010064,.009571,
.010464,.009,
.010759,.008368,
.010939,.007695,
.011,.007,
0.0*
%
%ADD128MACRO128*%
%AMMACRO160*
4,1,40,-.017,-.013,
-.017,.013,
-.016939,.013695,
-.016759,.014368,
-.016464,.015,
-.016064,.015571,
-.015571,.016064,
-.015,.016464,
-.014368,.016759,
-.013695,.016939,
-.013,.017,
.013,.017,
.013695,.016939,
.014368,.016759,
.015,.016464,
.015571,.016064,
.016064,.015571,
.016464,.015,
.016759,.014368,
.016939,.013695,
.017,.013,
.017,-.013,
.016939,-.013695,
.016759,-.014368,
.016464,-.015,
.016064,-.015571,
.015571,-.016064,
.015,-.016464,
.014368,-.016759,
.013695,-.016939,
.013,-.017,
-.013,-.017,
-.013695,-.016939,
-.014368,-.016759,
-.015,-.016464,
-.015571,-.016064,
-.016064,-.015571,
-.016464,-.015,
-.016759,-.014368,
-.016939,-.013695,
-.017,-.013,
0.0*
%
%ADD160MACRO160*%
%AMMACRO156*
4,1,40,.013,-.017,
-.013,-.017,
-.013695,-.016939,
-.014368,-.016759,
-.015,-.016464,
-.015571,-.016064,
-.016064,-.015571,
-.016464,-.015,
-.016759,-.014368,
-.016939,-.013695,
-.017,-.013,
-.017,.013,
-.016939,.013695,
-.016759,.014368,
-.016464,.015,
-.016064,.015571,
-.015571,.016064,
-.015,.016464,
-.014368,.016759,
-.013695,.016939,
-.013,.017,
.013,.017,
.013695,.016939,
.014368,.016759,
.015,.016464,
.015571,.016064,
.016064,.015571,
.016464,.015,
.016759,.014368,
.016939,.013695,
.017,.013,
.017,-.013,
.016939,-.013695,
.016759,-.014368,
.016464,-.015,
.016064,-.015571,
.015571,-.016064,
.015,-.016464,
.014368,-.016759,
.013695,-.016939,
.013,-.017,
0.0*
%
%ADD156MACRO156*%
%AMMACRO122*
4,1,21,.004,.01,
.003939,.010695,
.003759,.011368,
.003464,.012,
.003064,.012571,
.002571,.013064,
.002,.013464,
.001368,.013759,
.000695,.013939,
0.0,.014,
-.000695,.013939,
-.001368,.013759,
-.002,.013464,
-.002571,.013064,
-.003064,.012571,
-.003464,.012,
-.003759,.011368,
-.003939,.010695,
-.004,.01,
-.004,-.014,
.004,-.014,
.004,.01,
0.0*
%
%ADD122MACRO122*%
%AMMACRO121*
4,1,21,.01,-.004,
.010695,-.003939,
.011368,-.003759,
.012,-.003464,
.012571,-.003064,
.013064,-.002571,
.013464,-.002,
.013759,-.001368,
.013939,-.000695,
.014,0.0,
.013939,.000695,
.013759,.001368,
.013464,.002,
.013064,.002571,
.012571,.003064,
.012,.003464,
.011368,.003759,
.010695,.003939,
.01,.004,
-.014,.004,
-.014,-.004,
.01,-.004,
0.0*
%
%ADD121MACRO121*%
%AMMACRO222*
4,1,40,.008,-.012,
-.008,-.012,
-.008695,-.011939,
-.009368,-.011759,
-.01,-.011464,
-.010571,-.011064,
-.011064,-.010571,
-.011464,-.01,
-.011759,-.009368,
-.011939,-.008695,
-.012,-.008,
-.012,.008,
-.011939,.008695,
-.011759,.009368,
-.011464,.01,
-.011064,.010571,
-.010571,.011064,
-.01,.011464,
-.009368,.011759,
-.008695,.011939,
-.008,.012,
.008,.012,
.008695,.011939,
.009368,.011759,
.01,.011464,
.010571,.011064,
.011064,.010571,
.011464,.01,
.011759,.009368,
.011939,.008695,
.012,.008,
.012,-.008,
.011939,-.008695,
.011759,-.009368,
.011464,-.01,
.011064,-.010571,
.010571,-.011064,
.01,-.011464,
.009368,-.011759,
.008695,-.011939,
.008,-.012,
0.0*
%
%ADD222MACRO222*%
%AMMACRO105*
4,1,40,.012,.008,
.012,-.008,
.011939,-.008695,
.011759,-.009368,
.011464,-.01,
.011064,-.010571,
.010571,-.011064,
.01,-.011464,
.009368,-.011759,
.008695,-.011939,
.008,-.012,
-.008,-.012,
-.008695,-.011939,
-.009368,-.011759,
-.01,-.011464,
-.010571,-.011064,
-.011064,-.010571,
-.011464,-.01,
-.011759,-.009368,
-.011939,-.008695,
-.012,-.008,
-.012,.008,
-.011939,.008695,
-.011759,.009368,
-.011464,.01,
-.011064,.010571,
-.010571,.011064,
-.01,.011464,
-.009368,.011759,
-.008695,.011939,
-.008,.012,
.008,.012,
.008695,.011939,
.009368,.011759,
.01,.011464,
.010571,.011064,
.011064,.010571,
.011464,.01,
.011759,.009368,
.011939,.008695,
.012,.008,
0.0*
%
%ADD105MACRO105*%
%AMMACRO43*
4,1,40,-.007,.011,
.007,.011,
.007695,.010939,
.008368,.010759,
.009,.010464,
.009571,.010064,
.010064,.009571,
.010464,.009,
.010759,.008368,
.010939,.007695,
.011,.007,
.011,-.007,
.010939,-.007695,
.010759,-.008368,
.010464,-.009,
.010064,-.009571,
.009571,-.010064,
.009,-.010464,
.008368,-.010759,
.007695,-.010939,
.007,-.011,
-.007,-.011,
-.007695,-.010939,
-.008368,-.010759,
-.009,-.010464,
-.009571,-.010064,
-.010064,-.009571,
-.010464,-.009,
-.010759,-.008368,
-.010939,-.007695,
-.011,-.007,
-.011,.007,
-.010939,.007695,
-.010759,.008368,
-.010464,.009,
-.010064,.009571,
-.009571,.010064,
-.009,.010464,
-.008368,.010759,
-.007695,.010939,
-.007,.011,
0.0*
%
%ADD43MACRO43*%
%ADD226C,.006*%
G75*
%LPD*%
G75*
G36*
G01X13796Y458570D02*
Y449570D01*
X3896D01*
Y450870D01*
X6996D01*
Y452137D01*
X3896D01*
Y453437D01*
X6996D01*
Y454703D01*
X3896D01*
Y456003D01*
X6996D01*
Y457270D01*
X3896D01*
Y458570D01*
X13796D01*
G37*
G36*
G01X1371550Y337050D02*
X1357050D01*
Y351550D01*
X1371550D01*
Y337050D01*
G37*
G36*
G01X1752817Y567440D02*
X1760017D01*
Y560240D01*
X1752817D01*
Y567440D01*
G37*
G36*
G01X1835886Y67776D02*
Y58776D01*
X1825986D01*
Y60076D01*
X1829086D01*
Y61343D01*
X1825986D01*
Y62643D01*
X1829086D01*
Y63909D01*
X1825986D01*
Y65209D01*
X1829086D01*
Y66476D01*
X1825986D01*
Y67776D01*
X1835886D01*
G37*
G36*
G01X1806452Y539601D02*
X1813652D01*
Y532401D01*
X1806452D01*
Y539601D01*
G37*
G36*
G01X1814152Y597601D02*
Y590401D01*
X1806952D01*
Y597601D01*
X1814152D01*
G37*
G36*
G01X22900Y477898D02*
Y484198D01*
X26400D01*
Y477898D01*
X22900D01*
G37*
G36*
G01X1878090Y49550D02*
X1871790D01*
Y53050D01*
X1878090D01*
Y49550D01*
G37*
G54D100*
X637143Y327000D03*
X1391900Y232118D03*
X1386400Y237900D03*
X1403037Y302046D03*
X1391845Y348325D03*
X1390462Y541800D03*
X1400216Y560128D03*
X1413720Y301983D03*
X1418341Y494423D03*
Y477323D03*
X1442141Y477623D03*
X1442041Y489223D03*
X1507405Y518155D03*
X1498055Y516122D03*
X1509585Y510645D03*
X1500877Y508239D03*
X1492700Y520000D03*
X1542475Y509600D03*
X1548300Y511800D03*
X1594280Y472370D03*
X1885000Y227500D03*
X1918002Y98902D03*
X1934256Y99459D03*
X1913392Y149381D03*
X1909421Y208805D03*
X1903020Y225776D03*
G54D200*
X1887327Y511202D03*
X1929453Y532541D03*
G54D110*
X1250110Y336170D03*
G54D101*
X638108Y385368D03*
G54D120*
X1373950Y337213D03*
Y338788D03*
Y340363D03*
Y341938D03*
Y343513D03*
Y345087D03*
Y346662D03*
Y348237D03*
Y349812D03*
Y351387D03*
G54D210*
X1941937Y139548D03*
Y145452D03*
Y143484D03*
X1929937Y145452D03*
Y143484D03*
Y141516D03*
Y139548D03*
X1941937Y141516D03*
X1956376Y145503D03*
Y143535D03*
Y141567D03*
Y139599D03*
X1968376D03*
Y145503D03*
Y143535D03*
Y141567D03*
G54D111*
X1224391Y365477D03*
G54D201*
X1894689Y518328D03*
G54D102*
X628589Y463649D03*
X629359Y469583D03*
X632771Y473269D03*
X605176Y487581D03*
X641107Y471989D03*
X634033Y467638D03*
X695790Y351300D03*
X814849Y205001D03*
X792514Y201290D03*
X797717Y201907D03*
X803134Y202969D03*
X808165Y203529D03*
X818960Y202230D03*
X1937100Y146900D03*
G54D121*
X1354650Y340363D03*
Y338788D03*
Y337213D03*
Y351387D03*
Y349812D03*
Y348237D03*
Y346662D03*
Y345087D03*
Y343513D03*
Y341938D03*
G54D10*
X0Y0D03*
G54D130*
X1456250Y209500D03*
X1432750Y217180D03*
Y209500D03*
Y201820D03*
X1456250D03*
Y217180D03*
Y204380D03*
Y206940D03*
Y212060D03*
Y214620D03*
X1432750Y204380D03*
Y206940D03*
Y212060D03*
Y214620D03*
X1457838Y176527D03*
X1434338Y184207D03*
Y176527D03*
Y168847D03*
X1457838D03*
Y184207D03*
Y171407D03*
Y173967D03*
Y179087D03*
Y181647D03*
X1434338Y171407D03*
Y173967D03*
Y179087D03*
Y181647D03*
X1458250Y232000D03*
X1434750Y239680D03*
Y232000D03*
Y224320D03*
X1458250D03*
Y239680D03*
Y226880D03*
Y229440D03*
Y234560D03*
Y237120D03*
X1434750Y226880D03*
Y229440D03*
Y234560D03*
Y237120D03*
X1484750Y205750D03*
Y198250D03*
X1506250Y200750D03*
Y208250D03*
X1484750Y215750D03*
X1506250D03*
X1484750Y208250D03*
Y210750D03*
Y200750D03*
Y203250D03*
X1506250D03*
Y205750D03*
Y210750D03*
Y213250D03*
Y198250D03*
X1484750Y213250D03*
X1485450Y232250D03*
Y224750D03*
X1506950Y227250D03*
Y234750D03*
X1485450Y242250D03*
X1506950D03*
X1485450Y234750D03*
Y237250D03*
Y227250D03*
Y229750D03*
X1506950D03*
Y232250D03*
Y237250D03*
Y239750D03*
Y224750D03*
X1485450Y239750D03*
X1703250Y62680D03*
Y55000D03*
Y47320D03*
Y49880D03*
Y52440D03*
Y57560D03*
Y60120D03*
X1726750Y55000D03*
Y47320D03*
Y62680D03*
Y49880D03*
Y52440D03*
Y57560D03*
Y60120D03*
G54D220*
X1899369Y237015D03*
G54D211*
X1954041Y156109D03*
X1948921D03*
X1951481D03*
X1948921Y163364D03*
X1954041D03*
X1968871Y156309D03*
X1963751D03*
X1966311D03*
X1963751Y163564D03*
X1968871D03*
G54D202*
X1866730Y509560D03*
Y527560D03*
X1871850Y509560D03*
Y527560D03*
X1869290Y509560D03*
Y527560D03*
X1874410Y509560D03*
Y527560D03*
G54D112*
X1238475Y360530D03*
G54D103*
X634137Y404629D03*
G54D122*
X1357213Y334650D03*
X1358788D03*
X1360363D03*
X1361938D03*
X1363513D03*
X1365087D03*
X1366662D03*
X1368237D03*
X1369812D03*
X1371387D03*
G54D131*
X1456476Y278324D03*
Y275174D03*
X1459627Y300373D03*
Y297223D03*
X1481672Y278329D03*
Y275179D03*
X1475365Y300366D03*
Y297216D03*
X1468429Y289284D03*
Y286134D03*
X1472223Y287778D03*
Y284628D03*
X1481672Y306679D03*
Y303529D03*
X1520225Y440375D03*
Y437225D03*
X1517075Y443525D03*
Y440375D03*
X1523375D03*
Y437225D03*
X1526525Y440375D03*
Y437225D03*
X1513925Y443525D03*
Y440375D03*
X1510775Y443525D03*
Y440375D03*
X1504240Y416556D03*
Y413406D03*
X1532825Y452975D03*
Y449825D03*
X1539125Y452975D03*
Y449825D03*
X1542275Y440375D03*
Y437225D03*
X1535975Y440375D03*
Y437225D03*
X1532825Y440375D03*
Y437225D03*
X1539125Y421475D03*
Y418325D03*
X1532825Y421475D03*
Y418325D03*
G54D221*
X1912342Y481228D03*
G54D11*
X-16100Y25200D03*
X-16016Y45478D03*
X-15700Y35500D03*
X-15950Y55460D03*
X-8500Y25200D03*
X-8416Y45478D03*
X-8100Y35500D03*
X-8350Y55460D03*
X722268Y35902D03*
X720800Y523000D03*
X729868Y35902D03*
X751800Y213500D03*
X744200D03*
X728400Y523000D03*
X1390831Y97354D03*
X1383231D03*
X1398120Y378198D03*
Y370363D03*
X1374084Y555453D03*
X1366484D03*
X1396115Y557832D03*
X1388515D03*
X1396115Y565472D03*
X1388515D03*
X1395490Y532250D03*
X1403090D03*
X1395862Y542932D03*
X1403462D03*
X1405720Y378198D03*
Y370363D03*
X1464300Y598500D03*
X1456700D03*
X1872100Y162100D03*
X1879700D03*
X1872140Y169749D03*
X1879740D03*
X1870900Y179700D03*
X1878500D03*
X1871000Y191100D03*
X1878600D03*
G54D104*
X671371Y193310D03*
G54D140*
X1410808Y472742D03*
G54D212*
X1949650Y220787D03*
Y228661D03*
G54D113*
X1246438Y366646D03*
G54D20*
X30500Y-42250D03*
Y-52250D03*
X50500Y-42250D03*
X70500D03*
X90500D03*
X110500D03*
X50500Y-52250D03*
X70500D03*
X90500D03*
X110500D03*
X60512Y467244D03*
X130500Y-42250D03*
Y-52250D03*
X457246Y-52301D03*
Y-42301D03*
X477246Y-52301D03*
Y-42301D03*
X497246Y-52301D03*
Y-42301D03*
X517246Y-52301D03*
Y-42301D03*
X537246Y-52301D03*
Y-42301D03*
X557246Y-52301D03*
Y-42301D03*
X788984Y-52057D03*
Y-42057D03*
X808984Y-52057D03*
Y-42057D03*
X828984Y-52057D03*
Y-42057D03*
X848984Y-52057D03*
Y-42057D03*
X868984Y-52057D03*
Y-42057D03*
X888984Y-52057D03*
Y-42057D03*
X1125583Y-52285D03*
Y-42285D03*
X1145583Y-52285D03*
Y-42285D03*
X1382258Y-52257D03*
Y-42257D03*
X1402258Y-52257D03*
Y-42257D03*
X1422258Y-52257D03*
Y-42257D03*
X1442258Y-52257D03*
Y-42257D03*
X1891086Y592105D03*
X1904100Y493000D03*
G54D203*
X1872938Y483295D03*
Y485263D03*
Y489200D03*
Y491169D03*
X1875237Y483295D03*
Y485263D03*
Y489200D03*
Y491169D03*
X1960252Y180204D03*
Y182172D03*
Y186109D03*
Y188078D03*
X1962551Y180204D03*
Y182172D03*
Y186109D03*
Y188078D03*
G54D105*
X699050Y226500D03*
X1367239Y8476D03*
X1366860Y40490D03*
X1352457Y360095D03*
X1369307Y399408D03*
X1371060Y587276D03*
X1367450Y616400D03*
X1420000Y558398D03*
X1427901Y558435D03*
X1560929Y618572D03*
X1569307Y618555D03*
G54D222*
X1912342Y477628D03*
G54D123*
X1371387Y353950D03*
X1369812D03*
X1368237D03*
X1366662D03*
X1365087D03*
X1363513D03*
X1361938D03*
X1360363D03*
X1358788D03*
X1357213D03*
G54D150*
X1567299Y215920D03*
Y210920D03*
Y205920D03*
Y200920D03*
Y195920D03*
Y190920D03*
Y185920D03*
X1530149D03*
Y190920D03*
Y195920D03*
Y200920D03*
Y205920D03*
Y210920D03*
Y215920D03*
X1567299Y220920D03*
X1530149D03*
G54D204*
X1874087Y487232D03*
X1961401Y184141D03*
G54D132*
X1450182Y275181D03*
Y278331D03*
X1459628Y281473D03*
Y284623D03*
X1462777Y294072D03*
Y297222D03*
X1462775Y281470D03*
Y284620D03*
X1465949Y294050D03*
Y297200D03*
X1484822Y275177D03*
Y278327D03*
X1478523Y303521D03*
Y306671D03*
X1469000Y294100D03*
Y297250D03*
X1472226Y294076D03*
Y297226D03*
X1475373Y284626D03*
Y287776D03*
X1523375Y443525D03*
Y446675D03*
X1510775Y415175D03*
Y418325D03*
X1507625Y415175D03*
Y418325D03*
X1539125Y443525D03*
Y446675D03*
X1535975Y443525D03*
Y446675D03*
X1549805Y416465D03*
Y419615D03*
X1535975Y421475D03*
Y424625D03*
X1539125Y412025D03*
Y415175D03*
G54D114*
X1228715Y362963D03*
G54D30*
X-7874Y216181D03*
Y325315D03*
G54D141*
X1526871Y23968D03*
X1800986Y523267D03*
X1800985Y602503D03*
X1809665Y618663D03*
X1819665D03*
X1829665D03*
X1881595Y23968D03*
G54D21*
X40500Y-42250D03*
Y-52250D03*
X10512Y467244D03*
X20512D03*
X30512D03*
X40512D03*
X60500Y-42250D03*
X80500D03*
X100500D03*
X60500Y-52250D03*
X80500D03*
X100500D03*
X50512Y467244D03*
X120500Y-42250D03*
X140500D03*
X120500Y-52250D03*
X140500D03*
X467246Y-52301D03*
Y-42301D03*
X487246Y-52301D03*
Y-42301D03*
X507246Y-52301D03*
Y-42301D03*
X527246Y-52301D03*
Y-42301D03*
X547246Y-52301D03*
Y-42301D03*
X567246Y-52301D03*
Y-42301D03*
X798984Y-52057D03*
Y-42057D03*
X818984Y-52057D03*
Y-42057D03*
X838984Y-52057D03*
Y-42057D03*
X858984Y-52057D03*
Y-42057D03*
X878984Y-52057D03*
Y-42057D03*
X898984Y-52057D03*
Y-42057D03*
X1135583Y-52285D03*
Y-42285D03*
X1155583Y-52285D03*
Y-42285D03*
X1392258Y-52257D03*
Y-42257D03*
X1412258Y-52257D03*
Y-42257D03*
X1432258Y-52257D03*
Y-42257D03*
X1452258Y-52257D03*
Y-42257D03*
X1884100Y493000D03*
X1894100D03*
X1891086Y612105D03*
Y602105D03*
G54D213*
X1956890Y211535D03*
X1961890Y211043D03*
Y238405D03*
G54D12*
X-15250Y71330D03*
X-5210D03*
G54D160*
X1616849Y104338D03*
G54D133*
X1462770Y287777D03*
X1459620D03*
X1456477Y303528D03*
X1453327D03*
X1525900Y452400D03*
X1520225Y424625D03*
X1517075D03*
X1520225Y427775D03*
X1517075D03*
X1523550Y411600D03*
X1520400D03*
X1520225Y421475D03*
X1517075D03*
X1529050Y452400D03*
X1554875Y434075D03*
X1551725D03*
X1542275Y424625D03*
X1539125D03*
X1542275Y427775D03*
X1539125D03*
X1546000Y406800D03*
X1542850D03*
G54D106*
X695450Y226500D03*
X1363639Y8476D03*
X1363260Y40490D03*
X1348857Y360095D03*
X1365707Y399408D03*
X1367460Y587276D03*
X1363850Y616400D03*
X1416400Y558398D03*
X1424301Y558435D03*
X1557329Y618572D03*
X1565707Y618555D03*
G54D40*
X17300Y450210D03*
X1839390Y59416D03*
G54D124*
X1402430Y483176D03*
G54D31*
X18228Y178386D03*
X-1969D03*
X133563Y183126D03*
Y419626D03*
X783171Y183126D03*
Y419626D03*
X1454685Y338189D03*
X1600355Y527165D03*
G54D151*
X1589000Y298000D03*
X1572820D03*
X1589000Y303120D03*
X1572820D03*
X1589000Y300560D03*
X1572820D03*
Y305680D03*
X1589000D03*
X1864804Y568068D03*
Y565508D03*
Y562948D03*
X1887004Y542468D03*
Y545028D03*
Y547588D03*
Y550148D03*
Y552708D03*
Y555268D03*
X1864804Y557828D03*
Y555268D03*
Y552708D03*
Y550148D03*
Y547588D03*
Y545028D03*
Y542468D03*
Y539908D03*
X1887004Y557828D03*
Y560388D03*
Y568068D03*
Y539908D03*
Y562948D03*
Y565508D03*
X1864804Y560388D03*
G54D142*
X1490300Y22700D03*
X1478300D03*
X1906000Y564600D03*
X1918000D03*
X1906000Y582000D03*
X1918000D03*
X1906000Y573300D03*
X1918000D03*
X1906000Y590700D03*
X1918000D03*
G54D205*
X1856950Y488500D03*
Y491650D03*
X1864950D03*
Y488500D03*
X1919780Y236286D03*
Y239436D03*
X1927780D03*
Y236286D03*
X1911755Y228753D03*
Y231903D03*
X1919755D03*
Y228753D03*
G36*
G01X1956463Y209274D02*
G02X1954500Y205493I-1963J-1381D01*
G01X1950000D01*
G02X1947600Y207893I0J2400D01*
G01Y210293D01*
G02X1952400I2400J0D01*
G01X1954500D01*
G02X1954986Y210243I-1J-2400D01*
G03X1956463Y209274I1904J1292D01*
G37*
G54D115*
X1233239Y366212D03*
G54D223*
X1952756Y558464D03*
G54D22*
X16117Y-43892D03*
X8543Y636173D03*
X1926693Y646063D03*
G54D13*
X-15748Y101221D03*
Y116969D03*
Y132717D03*
Y148465D03*
Y357362D03*
Y373110D03*
Y388858D03*
Y404606D03*
X12205Y156339D03*
X-4331D03*
X17323Y101221D03*
Y116969D03*
Y132717D03*
Y148465D03*
X787Y101221D03*
Y116969D03*
Y132717D03*
Y148465D03*
X33858Y101221D03*
Y116969D03*
Y132717D03*
Y148465D03*
X28740Y109095D03*
Y124843D03*
Y140591D03*
Y156339D03*
X12205Y109095D03*
Y124843D03*
Y140591D03*
X-4331Y109095D03*
Y124843D03*
Y140591D03*
X17323Y357362D03*
Y373110D03*
Y388858D03*
Y404606D03*
X787Y357362D03*
Y373110D03*
Y388858D03*
Y404606D03*
X33858Y357362D03*
Y373110D03*
Y388858D03*
Y404606D03*
X28740Y365236D03*
Y380984D03*
Y396732D03*
X12205Y365236D03*
Y380984D03*
Y396732D03*
X-4331Y365236D03*
Y380984D03*
Y396732D03*
X12205Y412480D03*
X-4331D03*
X28740D03*
G54D152*
X1548127Y414127D03*
X1545900Y411900D03*
G54D170*
X1703100Y135246D03*
X1690860Y124143D03*
G54D206*
X1887327Y532541D03*
X1929453Y511202D03*
G54D32*
X44291Y178386D03*
G54D215*
X1915031Y208449D03*
X1922431D03*
G54D224*
X1899972Y615413D03*
Y609913D03*
G54D143*
X1527233Y57198D03*
Y41018D03*
X1551107Y65716D03*
X1548547D03*
X1545987D03*
X1543427D03*
Y49536D03*
X1545987D03*
X1548547D03*
X1551107D03*
X1534913Y57198D03*
X1532353D03*
X1529793D03*
Y41018D03*
X1532353D03*
X1534913D03*
G54D41*
X37000Y515600D03*
X48000D03*
X1728050Y255900D03*
X1739050D03*
G54D134*
X1453327Y306678D03*
X1456477D03*
X1491925Y270500D03*
X1495075D03*
X1515050Y403500D03*
X1518200D03*
X1513925Y415175D03*
X1517075D03*
X1503925Y427100D03*
X1507075D03*
X1507625Y437225D03*
X1510775D03*
X1530350Y411300D03*
X1533500D03*
X1544225Y433200D03*
X1547375D03*
G54D116*
X1242459Y344788D03*
G54D107*
X1229071Y340046D03*
G54D50*
X72800Y105000D03*
G54D125*
X1462000Y-5000D03*
Y-15000D03*
X1452000Y-5000D03*
Y-15000D03*
X1442000Y-5000D03*
X1525000Y-15000D03*
X1515000D03*
X1482000D03*
X1472000Y-5000D03*
Y-15000D03*
X1492000Y-5000D03*
Y-15000D03*
X1482000Y-5000D03*
X1575000Y-15000D03*
X1565000D03*
X1555000D03*
X1545000D03*
X1535000D03*
X1713503Y-5000D03*
Y-15000D03*
X1703503Y-5000D03*
X1743503Y-15000D03*
X1733503Y-5000D03*
Y-15000D03*
X1723503Y-5000D03*
Y-15000D03*
X1753503Y-5000D03*
Y-15000D03*
X1743503Y-5000D03*
X1769504D03*
X1809504Y-15000D03*
X1799504Y-5000D03*
Y-15000D03*
X1789504Y-5000D03*
Y-15000D03*
X1779504Y-5000D03*
Y-15000D03*
X1819504Y-5000D03*
Y-15000D03*
X1809504Y-5000D03*
G54D14*
X-15354Y109095D03*
Y124843D03*
Y140591D03*
Y156339D03*
Y365236D03*
Y380984D03*
Y396732D03*
Y412480D03*
X22835Y101221D03*
X6299D03*
X-10236D03*
X17716Y109095D03*
X1181D03*
X22835Y116969D03*
X6299D03*
X1181Y124843D03*
X22835Y132717D03*
X1181Y140591D03*
X22835Y148465D03*
X6299D03*
X-10236D03*
X17716Y156339D03*
X1181D03*
X-10236Y116969D03*
X-4725D03*
X23228Y124843D03*
X17716D03*
X-10236Y132717D03*
X-4725D03*
X6299D03*
X11811D03*
X17716Y140591D03*
X23228D03*
X-9843Y156339D03*
X23228Y109095D03*
X6693D03*
Y124843D03*
X-9843Y109095D03*
Y124843D03*
X-4725Y101221D03*
X11811Y148465D03*
Y101221D03*
Y116969D03*
X28346Y101221D03*
Y116969D03*
Y132717D03*
X6693Y140591D03*
X-9843D03*
X28346Y148465D03*
X6693Y156339D03*
X-4725Y148465D03*
X23228Y156339D03*
X22835Y357362D03*
X6299D03*
X-10236D03*
X17716Y365236D03*
X1181D03*
X22835Y373110D03*
X6299D03*
X1181Y380984D03*
X22835Y388858D03*
X1181Y396732D03*
X22835Y404606D03*
X6299D03*
X-10236D03*
Y373110D03*
X-4725D03*
X23228Y380984D03*
X17716D03*
X-10236Y388858D03*
X-4725D03*
X6299D03*
X11811D03*
X17716Y396732D03*
X23228D03*
Y365236D03*
X6693D03*
Y380984D03*
X-9843Y365236D03*
Y380984D03*
X-4725Y357362D03*
X11811Y404606D03*
Y357362D03*
Y373110D03*
X28346Y357362D03*
Y373110D03*
Y388858D03*
X6693Y396732D03*
X-9843D03*
X28346Y404606D03*
X-4725D03*
X17716Y412480D03*
X1181D03*
X-9843D03*
X6693D03*
X23228D03*
G54D23*
G01X430749Y-124922D02*
G02I-12000J0D01*
G01X425599D02*
G02I-6850J0D01*
G01X434749D02*
X402749D01*
G01X434749Y-140922D02*
Y-220922D01*
G01D02*
X1729349D01*
G01X434749Y-176422D02*
X1729349D01*
G01X418749Y-140922D02*
Y-108922D01*
G01X434749Y-140922D02*
X1729349D01*
G01X941849D02*
Y-220922D01*
G01X1079349Y-140922D02*
Y-220922D01*
G01X1194349Y-140922D02*
Y-220922D01*
G01X1361849Y-140922D02*
Y-220922D01*
G01X1531849Y-140922D02*
Y-220922D01*
G01X1729349Y-140922D02*
Y-220922D01*
G01X1757349Y-124922D02*
G02I-12000J0D01*
G01X1752199D02*
G02I-6850J0D01*
G01X1745349Y-140922D02*
Y-108922D01*
G01X1761349Y-124922D02*
X1729349D01*
X37739Y19501D03*
X13716Y24861D03*
X1382Y68100D03*
X44310Y268160D03*
X33490Y267900D03*
X24591Y479139D03*
X54307Y-8051D03*
X62486Y-19184D03*
X65384Y109750D03*
Y104750D03*
X65405Y118730D03*
X60831Y144750D03*
X65687Y132750D03*
X60831Y130750D03*
X60700Y116750D03*
X60801Y97750D03*
X60831Y139750D03*
X65687Y137750D03*
X60831Y125750D03*
X65405Y123730D03*
X60700Y111750D03*
X60801Y102750D03*
X95275Y217545D03*
X91626Y215364D03*
X85156Y212774D03*
X89386Y212744D03*
X87416Y215504D03*
X87542Y210043D03*
X83366Y215624D03*
X95140Y220946D03*
X91809Y221009D03*
X88447Y221136D03*
X85188Y221341D03*
X72074Y243282D03*
X65180Y243368D03*
X61800Y243400D03*
X68498Y243368D03*
X62900Y339000D03*
X102040Y348960D03*
X49560Y649770D03*
Y644670D03*
X54360D03*
X49560Y649570D03*
Y644670D03*
X54360D03*
X49560Y654670D03*
X54360D03*
X49560D03*
X54360D03*
X141880Y-4651D03*
X109622Y128879D03*
X118220Y360500D03*
X118629Y381193D03*
X141880Y569340D03*
Y609749D03*
X178691Y-7260D03*
X215502Y531540D03*
X178691D03*
X173591Y534399D03*
X215502Y571949D03*
X178691D03*
X214820Y649570D03*
Y644670D03*
X210020D03*
X214820Y649770D03*
Y644670D03*
X210020D03*
X178691Y607140D03*
X210402Y609999D03*
X214820Y654670D03*
X210020D03*
X214820D03*
X210020D03*
X247239Y-7050D03*
X284024Y-4401D03*
X284050Y30750D03*
X289124Y30540D03*
X252313Y68340D03*
X271239Y207159D03*
X291519Y320260D03*
X284759D03*
X291519Y324160D03*
X277999D03*
X264179Y331960D03*
X271239D03*
X267859Y345609D03*
X247239Y531750D03*
X284024Y534399D03*
X252313Y569340D03*
X247213Y572199D03*
X289124Y571949D03*
X284050Y569550D03*
X238282Y649670D03*
Y644770D03*
X243082D03*
X238282Y649870D03*
Y644770D03*
X243082D03*
X284024Y609999D03*
X247213D03*
X238282Y654770D03*
X243082D03*
X238282D03*
X243082D03*
X331100Y-9786D03*
X311021Y-4536D03*
X347833Y-1743D03*
X311021Y35957D03*
X334446Y65814D03*
X334447Y35957D03*
X347833D03*
X332078Y226660D03*
X315178Y244209D03*
X311798Y246160D03*
X321938Y252009D03*
X345598Y242260D03*
X335458Y232510D03*
X352357Y250060D03*
X345598D03*
X342218Y248109D03*
X335458Y240309D03*
X338838Y261760D03*
X335458Y255909D03*
X355737Y252009D03*
X348978D03*
X352357Y253960D03*
X345598D03*
X355737Y255909D03*
X348978D03*
X345598Y261760D03*
X348978Y259809D03*
X345598Y257860D03*
X352357D03*
X342218Y252009D03*
X338838Y250060D03*
X345598Y234460D03*
X352357Y242260D03*
X298279Y324160D03*
X294899Y326109D03*
X321938Y341709D03*
X335458Y322209D03*
X308418Y349509D03*
X332078Y367060D03*
X321938Y345609D03*
X342218Y349509D03*
X345598Y347560D03*
X335458Y365109D03*
X352357Y347560D03*
X326922Y497170D03*
X344486Y529022D03*
Y536957D03*
X354525Y529022D03*
X334447Y536957D03*
X324407Y529014D03*
X314368Y566814D03*
X321061D03*
X344486Y566822D03*
Y609864D03*
X364565Y-9786D03*
X414761Y-7108D03*
X361218Y-1858D03*
X364565Y28014D03*
X414762Y28021D03*
X364565Y35942D03*
X404723Y35957D03*
X365877Y242260D03*
X372637D03*
X362497Y248109D03*
X359117Y250060D03*
X389537Y240309D03*
X382777D03*
X386157Y242260D03*
X379397D03*
X389537Y244209D03*
X382777D03*
X376017D03*
X386157Y246160D03*
X379397D03*
X372637D03*
X365877D03*
X369257Y248109D03*
X365877Y250060D03*
X359117Y253960D03*
X362497Y252009D03*
X399676Y242260D03*
X392916D03*
Y246160D03*
X396296Y244209D03*
Y240309D03*
X359117Y242260D03*
X379397Y351460D03*
X362497Y349509D03*
X376017D03*
X382777Y353409D03*
Y357309D03*
X379397Y355360D03*
X359117Y347560D03*
X396296Y357309D03*
X399676Y355360D03*
X369257Y361209D03*
X376017Y357309D03*
X361642Y515200D03*
X361518Y510114D03*
X408069Y529007D03*
X364565Y574742D03*
Y566814D03*
X401377Y536957D03*
X414763D03*
Y566822D03*
X402404Y649650D03*
Y644550D03*
X397604D03*
X402404Y649450D03*
Y644550D03*
X397604D03*
X398029Y604499D03*
X361218Y604614D03*
X414763Y593657D03*
X402404Y654550D03*
X397604D03*
X402404D03*
X397604D03*
X431494Y28007D03*
X438187Y-9786D03*
X424801D03*
X444880Y-4536D03*
X438189Y28022D03*
X444882Y35957D03*
X434842Y73757D03*
X422594Y235696D03*
Y247396D03*
X429354Y239596D03*
X443993Y370247D03*
X437233Y378047D03*
X440613Y376096D03*
X443993Y374147D03*
X464273Y342947D03*
X457513Y350747D03*
X460893Y344896D03*
X474413D03*
X464732Y534399D03*
X469832Y531540D03*
X424801Y566807D03*
X464732Y572199D03*
X444882Y536957D03*
X434842D03*
X421456Y529022D03*
X444880Y566822D03*
X425750Y649400D03*
Y644500D03*
X430550D03*
X425750Y649600D03*
Y644500D03*
X430550D03*
X474998Y604499D03*
X444880Y604614D03*
X431494Y604499D03*
X464758Y607350D03*
X438187Y593659D03*
X425750Y654500D03*
X430550D03*
X425750D03*
X430550D03*
X501543Y33399D03*
X506643Y30540D03*
X538355Y-4401D03*
X518352Y210345D03*
X528491Y212296D03*
X494692D03*
X501452Y216196D03*
X504832Y218147D03*
X511592Y214247D03*
X514972Y216196D03*
X518352Y214247D03*
X531871D03*
X514972Y212296D03*
Y208397D03*
X521731Y212296D03*
X525111Y210346D03*
X504832Y214247D03*
X498072D03*
X508212Y216196D03*
X535251Y212296D03*
X483432Y220096D03*
X480052Y222047D03*
X501452Y251296D03*
Y255196D03*
X491312Y280547D03*
X486812Y261047D03*
X483432Y262996D03*
X498072Y280547D03*
X511592Y272747D03*
X504832Y276647D03*
X498072D03*
X491312D03*
X511592D03*
X504832Y272747D03*
X498072Y253247D03*
Y257147D03*
X504832Y280547D03*
X511592D03*
X498072Y272747D03*
X501452Y262996D03*
X498072Y261047D03*
X494692Y259096D03*
X525111Y249347D03*
X528491Y251296D03*
X525111Y241547D03*
X528491Y239596D03*
X531871Y253247D03*
X521731Y262996D03*
X525111Y264947D03*
X528491Y266896D03*
X521731Y278596D03*
X518352Y280547D03*
Y276646D03*
X484552D03*
X504832Y249347D03*
X501452Y270796D03*
X518352Y268847D03*
X538631Y276646D03*
Y245447D03*
X535251Y274696D03*
X494692Y239596D03*
Y231797D03*
X504832Y237647D03*
X508212Y227896D03*
X525111Y233746D03*
X511592Y237647D03*
X538631Y268847D03*
Y264947D03*
X531871Y245447D03*
X501452Y243496D03*
X535251Y262996D03*
X538631Y253247D03*
X531871Y280547D03*
X538631Y241547D03*
X521731Y270796D03*
X504832Y257147D03*
X508212Y251296D03*
X518352Y225947D03*
X531871Y233746D03*
Y225947D03*
X538631Y233746D03*
X531871Y272747D03*
X501452Y227896D03*
X514972Y231797D03*
X525111Y225947D03*
X494692Y220096D03*
X535251D03*
X504832Y222047D03*
X538631Y272747D03*
X491312Y288347D03*
Y284447D03*
X498072D03*
Y288347D03*
X501452Y286396D03*
X494692Y290296D03*
X498072Y292247D03*
X504832D03*
X508212Y282496D03*
X504832Y288347D03*
Y284447D03*
X494692Y282496D03*
X508212Y286396D03*
X511592Y292245D03*
X484552Y319546D03*
X481172Y333196D03*
X484552Y331247D03*
X514972Y282496D03*
X521731D03*
X518352Y284447D03*
X538631Y307847D03*
Y303947D03*
Y300047D03*
X535251Y298096D03*
Y305896D03*
X538631Y296147D03*
X531871D03*
X535251Y317596D03*
X525111Y315647D03*
X531871D03*
X535251Y313696D03*
X538631Y315647D03*
X528491Y282496D03*
X535251Y286396D03*
Y282496D03*
Y376096D03*
X518352Y401447D03*
X504832Y385847D03*
Y393647D03*
X508212Y376096D03*
X498072Y370247D03*
X504832D03*
X501452Y372197D03*
X518352Y405347D03*
X538381Y569550D03*
X506644Y531540D03*
Y571949D03*
X501570Y569550D03*
X538381Y607350D03*
X506644Y609749D03*
X501570Y607350D03*
X528155Y610300D03*
X575166Y-4401D03*
X580266Y30540D03*
X545391Y214247D03*
Y218147D03*
X548771Y216196D03*
X542011Y212296D03*
Y231797D03*
X548771D03*
X552151Y280547D03*
X548771Y274696D03*
Y220096D03*
X555531D03*
Y227896D03*
X542011Y278596D03*
Y262996D03*
X555531Y270796D03*
X552151Y264947D03*
X542011Y259096D03*
X545391Y257147D03*
Y249347D03*
X548771Y223996D03*
X542011Y243496D03*
X552151Y222047D03*
X562616Y223996D03*
X542011Y251296D03*
X545391Y245447D03*
X555531Y243496D03*
Y259096D03*
X552151Y253247D03*
X548771Y259096D03*
X562640Y231735D03*
X542011Y220096D03*
X575600Y259300D03*
X542011Y309797D03*
X545391Y311747D03*
X542011Y305896D03*
Y301996D03*
X552151Y311747D03*
X542011Y313696D03*
X548771Y321496D03*
X545391Y323446D03*
X552151Y319547D03*
Y315647D03*
X559211Y331103D03*
X555531Y329296D03*
X559211Y323446D03*
X555531Y321496D03*
X548771Y317596D03*
X555831Y313696D03*
X559211Y327347D03*
X552151D03*
X555531Y325396D03*
X555831Y317446D03*
X552151Y292245D03*
X559211Y284447D03*
X542011Y290296D03*
X560884D03*
X542011Y282496D03*
X552151Y366347D03*
Y370247D03*
X563500Y360500D03*
X555531Y372197D03*
X548771Y364396D03*
X552151Y393647D03*
X559212Y389747D03*
X548990Y403670D03*
X555750Y399770D03*
X580266Y534149D03*
X543455Y569340D03*
X575192Y569550D03*
X589871Y649379D03*
Y644279D03*
X585071D03*
X589872Y649180D03*
Y644280D03*
X585072D03*
X580266Y609749D03*
X543455D03*
X575192Y607350D03*
X564966Y610300D03*
X589871Y654279D03*
X585071D03*
X589872Y654280D03*
X585072D03*
X647000Y-12100D03*
X659747Y-12132D03*
X637561Y317000D03*
X637600Y302000D03*
X659694Y351206D03*
X649194D03*
X613298Y649331D03*
Y644231D03*
X618098D03*
X613298Y649131D03*
Y644231D03*
X618098D03*
X613298Y654231D03*
X618098D03*
X613298D03*
X618098D03*
X665396Y23000D03*
X713700Y224144D03*
X688924Y288147D03*
X668000Y298400D03*
X704404Y315875D03*
X748700Y257500D03*
X749800Y282300D03*
X746130Y430130D03*
X763544Y522236D03*
X782567Y534700D03*
X773228Y528899D03*
X791488Y569340D03*
X836810Y572900D03*
X819378Y572500D03*
X810039Y528899D03*
X823199Y534399D03*
X828299Y531540D03*
X833464Y528899D03*
X791488Y607140D03*
X846850Y604499D03*
X823225Y607350D03*
X870275Y528899D03*
X860010Y534399D03*
X849810Y572500D03*
X860010Y572199D03*
X910432Y535100D03*
X901921Y534149D03*
X886621Y572500D03*
X901921Y569340D03*
X896821Y572199D03*
X905515Y649159D03*
Y644259D03*
X900715D03*
X905515Y649359D03*
Y644259D03*
X900715D03*
X865110Y607140D03*
X883661Y604499D03*
X901921Y607140D03*
X905515Y654259D03*
X900715D03*
X905515D03*
X900715D03*
X944507Y205210D03*
Y209109D03*
X971546Y252009D03*
Y341709D03*
X944507Y326110D03*
X933632Y534399D03*
X943897Y528899D03*
X938732Y569340D03*
X933632Y572199D03*
X913779Y566699D03*
X917125Y572900D03*
X950590Y566699D03*
X963976Y566814D03*
X960629Y574757D03*
Y536957D03*
X970669Y529014D03*
X928952Y649120D03*
Y644220D03*
X933752D03*
X928952Y649320D03*
Y644220D03*
X933752D03*
X933658Y607350D03*
X960629Y609864D03*
X928952Y654220D03*
X933752D03*
X928952D03*
X933752D03*
X995206Y218860D03*
Y222760D03*
X1022245Y234460D03*
X991826Y240309D03*
X995206Y234460D03*
X1008725D03*
X1032385Y228610D03*
X998586Y341709D03*
Y345609D03*
X981686Y367060D03*
X978306Y372909D03*
X1029005Y355360D03*
X1015485Y351460D03*
X1012105Y349509D03*
X1025625D03*
X1001965Y343660D03*
X1018865Y369010D03*
X995206Y363160D03*
X1032385Y369010D03*
X987401Y509999D03*
X994094Y510114D03*
X1011250Y515200D03*
X1013873Y510114D03*
X1010826Y566814D03*
Y574742D03*
X984054Y529014D03*
X997441Y574757D03*
X987401D03*
X994094Y529022D03*
X1004133D03*
X984055Y607292D03*
X994094Y604614D03*
X1010826Y612242D03*
X1014173Y604614D03*
X1045904Y213009D03*
Y228610D03*
X1078962Y235696D03*
Y243496D03*
X1042524Y234460D03*
X1035765D03*
X1049284D03*
X1039145Y236409D03*
X1093601Y370247D03*
X1081102Y566807D03*
X1087797Y566822D03*
X1094490Y574757D03*
X1054331Y529022D03*
X1094490Y536957D03*
X1050983Y607292D03*
X1074409Y609864D03*
Y593642D03*
X1087795Y604614D03*
X1074409D03*
X1094488Y609864D03*
X1064369Y607292D03*
X1129660Y210346D03*
X1136420D03*
X1144300Y212296D03*
X1147680Y214247D03*
X1144300Y216196D03*
X1147680Y218147D03*
X1154440D03*
X1140920Y280547D03*
X1157820Y274696D03*
X1154440Y268847D03*
X1140920Y272747D03*
X1154440Y280547D03*
Y276647D03*
X1147680D03*
X1140920D03*
X1154440Y272747D03*
X1147680D03*
X1151060Y270796D03*
X1144300Y220096D03*
X1154440Y237647D03*
X1147680Y241547D03*
X1157820Y227896D03*
X1147680Y229847D03*
X1109381Y257147D03*
X1112761Y255196D03*
X1102621Y253247D03*
X1106001Y255196D03*
X1144300Y290296D03*
X1147680Y292247D03*
X1154440D03*
X1157820Y282496D03*
X1154440Y288347D03*
Y284447D03*
X1144300Y282496D03*
X1157820Y286396D03*
X1137540D03*
X1140920Y288347D03*
Y284447D03*
X1147680D03*
Y288347D03*
X1151060Y286396D03*
X1137540Y301996D03*
X1151060Y337096D03*
X1120641Y339047D03*
X1110501Y344896D03*
X1107121Y350747D03*
X1113881Y342947D03*
X1154440Y370246D03*
X1151060Y372196D03*
X1157820D03*
X1140920Y342947D03*
Y401447D03*
X1154440Y374146D03*
X1147680D03*
X1124021Y344896D03*
X1127400Y350747D03*
X1120641Y346847D03*
X1151060Y376096D03*
X1157820Y368296D03*
X1144300Y379996D03*
Y387796D03*
X1157820Y376096D03*
X1144300Y383896D03*
X1147680Y381947D03*
Y378047D03*
X1119440Y531540D03*
Y569340D03*
X1151178Y531750D03*
X1124606Y528899D03*
X1137992Y566699D03*
X1156252Y571949D03*
X1114340Y534399D03*
X1134645Y535100D03*
X1151152Y572199D03*
X1140952Y572500D03*
X1114340Y572199D03*
X1114366Y607350D03*
X1156252Y609749D03*
X1210070Y195300D03*
X1191619Y212296D03*
X1167960Y214247D03*
X1164580Y208397D03*
X1181479Y214247D03*
X1194999Y218147D03*
X1174719Y214247D03*
X1161200D03*
X1164580Y274696D03*
X1167960Y280547D03*
X1171339Y262996D03*
X1174719Y264947D03*
X1171339Y278596D03*
X1161200Y276646D03*
Y280547D03*
X1167960Y268847D03*
X1188239D03*
X1205139Y278596D03*
X1184859Y227896D03*
X1198379Y223996D03*
X1188239Y245447D03*
X1194999Y229847D03*
X1178099Y231797D03*
X1171339Y227896D03*
X1174719Y222047D03*
X1208519Y253247D03*
X1205139Y262996D03*
X1181479Y280547D03*
X1191619Y235696D03*
X1164580Y231797D03*
X1205139Y270796D03*
X1198379Y274696D03*
X1201759Y253247D03*
X1194999Y261047D03*
X1188239Y253247D03*
X1181479Y245447D03*
X1212199Y227896D03*
X1184859Y220096D03*
X1205139Y223996D03*
X1161200Y237647D03*
X1205139Y243496D03*
Y235696D03*
Y255196D03*
X1217476Y243482D03*
X1216234Y265555D03*
X1171339Y282496D03*
X1167960Y284447D03*
X1164580Y282496D03*
X1184859Y298096D03*
X1191619Y313696D03*
X1188239Y300047D03*
X1191619Y340996D03*
X1188239Y331247D03*
Y327347D03*
X1194999Y311747D03*
X1184859Y305896D03*
X1188239Y296147D03*
X1181479D03*
X1191619Y325396D03*
X1188239Y307847D03*
X1208819Y284447D03*
X1174719Y323446D03*
X1161200Y288347D03*
Y292247D03*
X1201759D03*
X1171339Y340996D03*
X1178099Y352696D03*
X1164580Y376096D03*
X1194999Y350747D03*
X1198379Y348796D03*
X1184859Y379996D03*
X1188239Y350747D03*
X1191619Y356596D03*
X1184859Y372197D03*
X1181479Y366347D03*
Y362447D03*
X1188239D03*
Y358547D03*
Y354647D03*
X1198379Y383896D03*
X1191619Y379996D03*
X1184859Y376096D03*
X1198379D03*
X1171339Y391696D03*
X1191619Y344896D03*
X1178099Y376096D03*
X1171339Y395596D03*
X1174719Y389747D03*
X1171339Y383896D03*
X1161200Y389747D03*
X1164580Y395597D03*
X1178099Y387796D03*
X1167960Y346847D03*
X1164580Y360496D03*
X1161200Y366347D03*
X1167960Y354647D03*
X1161200D03*
X1164580Y368296D03*
X1181479Y378047D03*
X1188239Y374146D03*
X1184859Y368296D03*
Y364396D03*
X1181479Y358547D03*
X1184859Y360496D03*
X1197100Y408200D03*
X1168110Y566699D03*
X1177763Y572500D03*
X1164763Y572900D03*
X1161417Y528899D03*
X1219041Y649348D03*
Y644248D03*
X1214241D03*
X1219041Y649148D03*
Y644248D03*
X1214241D03*
X1164763Y610700D03*
X1219041Y654248D03*
X1214241D03*
X1219041D03*
X1214241D03*
X1240000Y129500D03*
X1271500Y122500D03*
X1271490Y104700D03*
X1226785Y213003D03*
X1221300Y208000D03*
X1226500Y202400D03*
X1225908Y261800D03*
X1262900Y466504D03*
X1256320Y490660D03*
X1258126Y469540D03*
X1256350Y486080D03*
X1242450Y649150D03*
Y644250D03*
X1247250D03*
X1242450Y649350D03*
Y644250D03*
X1247250D03*
X1242450Y654250D03*
X1247250D03*
X1242450D03*
X1247250D03*
X1319888Y290205D03*
X1341375Y314675D03*
Y319675D03*
X1286831Y443058D03*
X1339900Y518900D03*
X1380219Y5581D03*
X1362674Y46058D03*
X1350100Y170000D03*
X1392226Y319458D03*
X1349134Y317436D03*
X1400558Y320157D03*
X1380904Y319747D03*
X1371090Y319195D03*
X1360294Y318825D03*
X1358500Y338400D03*
X1370200D03*
X1364300Y338300D03*
X1370300Y350200D03*
X1358300Y344200D03*
X1358400Y350100D03*
X1370200Y343900D03*
X1364100Y350200D03*
X1395375Y453561D03*
X1402775Y457561D03*
X1388741Y493623D03*
X1383241Y498595D03*
X1368441Y492723D03*
X1362880Y497556D03*
X1360863Y481673D03*
X1465237Y11563D03*
X1460237D03*
X1446340D03*
X1441340D03*
X1413387Y320033D03*
X1456900Y387600D03*
X1414107Y447267D03*
X1461600Y449997D03*
X1464400Y454100D03*
X1461800Y465500D03*
X1454000D03*
X1410475Y453561D03*
X1456600Y454100D03*
X1464400Y459800D03*
X1456600D03*
X1464553Y508872D03*
X1436441Y489323D03*
X1412741Y494223D03*
X1436541Y494423D03*
X1436600Y482900D03*
X1413193Y482532D03*
X1493770Y6909D03*
X1484135Y11563D03*
X1488770Y6909D03*
X1479135Y11563D03*
X1513335Y92921D03*
X1513935Y104532D03*
Y116343D03*
X1524575Y387654D03*
X1503878Y364717D03*
X1487525Y384274D03*
X1505075Y394414D03*
X1501175Y387654D03*
X1505075Y401174D03*
X1501175D03*
X1522625Y391034D03*
X1495325Y397794D03*
X1499225D03*
X1493375Y401174D03*
X1489475D03*
X1507025Y384274D03*
X1501175Y380894D03*
X1522625Y397794D03*
X1507025Y377514D03*
X1518725Y384274D03*
X1510925Y397794D03*
X1483868Y390233D03*
X1516775Y394414D03*
X1510925Y377514D03*
X1512875Y380894D03*
X1518725Y377514D03*
X1522625Y384274D03*
X1510925Y391034D03*
X1512875Y387654D03*
X1510925Y384274D03*
X1489475Y380894D03*
X1493375D03*
X1487525Y397794D03*
Y377514D03*
X1498183Y365405D03*
X1505075Y387654D03*
X1499225Y377514D03*
X1517367Y349964D03*
X1505075Y463826D03*
X1515500Y448250D03*
X1507025Y404554D03*
X1499225D03*
Y440166D03*
X1522625Y404554D03*
X1491425Y418074D03*
X1487525D03*
X1499225Y446926D03*
Y453686D03*
X1520675Y463826D03*
X1512875D03*
X1508975D03*
X1501175Y421454D03*
X1495325Y418074D03*
X1493375Y443546D03*
X1489475Y414694D03*
X1493375D03*
X1489475Y407934D03*
X1493375D03*
Y421454D03*
X1489475D03*
X1493375Y428214D03*
Y436786D03*
X1499225Y460446D03*
X1489475Y457066D03*
X1487525Y460446D03*
Y480726D03*
X1520675Y470586D03*
X1510925Y467206D03*
X1507025D03*
X1520675Y477346D03*
X1514825Y467206D03*
X1512875Y470586D03*
X1491425Y480726D03*
X1495325Y473966D03*
X1491425Y487486D03*
X1499225Y467206D03*
X1520675Y484106D03*
X1524575Y477346D03*
X1512875D03*
X1526525Y480726D03*
X1524575Y484106D03*
X1522625Y480726D03*
X1516775Y477346D03*
X1508626Y503038D03*
X1506985Y510645D03*
X1510005Y518155D03*
X1498277Y508239D03*
X1490100Y520000D03*
X1485693Y508000D03*
X1479375Y507975D03*
X1527739Y644278D03*
D03*
X1472932Y619131D03*
X1504700Y611100D03*
X1518900Y619800D03*
X1508550Y619810D03*
X1513700Y619900D03*
X1478500Y619300D03*
X1527739Y654278D03*
D03*
X1571500Y-1406D03*
X1573048Y12506D03*
X1581998Y11355D03*
X1554148Y12306D03*
X1563498Y12506D03*
X1544698D03*
X1573121Y120649D03*
X1540175Y387654D03*
X1551875D03*
X1565525Y397794D03*
X1528475Y401174D03*
Y387654D03*
Y394414D03*
X1530425Y377514D03*
X1534325Y384274D03*
Y397794D03*
Y377514D03*
X1542300Y376717D03*
X1551875Y394414D03*
X1540175Y380894D03*
Y401174D03*
X1536275D03*
X1540175Y394414D03*
X1563575Y387654D03*
X1551875Y401174D03*
X1559675Y380894D03*
X1563575D03*
X1565525Y384274D03*
X1586500Y358400D03*
X1587684Y362653D03*
X1565525Y460446D03*
X1567475Y414694D03*
Y443546D03*
Y463826D03*
X1565525Y453686D03*
Y418074D03*
X1571375Y421454D03*
X1569425Y418074D03*
X1565525Y424834D03*
X1571375Y414694D03*
Y407934D03*
X1565525Y446926D03*
X1528475Y463826D03*
X1559675D03*
X1542125Y460446D03*
X1536275Y463826D03*
X1555775Y407934D03*
X1561625Y411314D03*
Y440166D03*
X1551875Y443546D03*
X1557725Y460446D03*
X1553825D03*
X1563575Y450306D03*
X1546025Y460446D03*
X1563575Y463826D03*
X1557725Y440166D03*
Y418074D03*
X1563575Y421454D03*
X1567475Y477346D03*
X1565525Y473966D03*
X1569425Y467206D03*
X1565525D03*
X1571545Y482842D03*
X1571375Y477346D03*
X1530425Y467206D03*
X1561625D03*
X1563575Y470586D03*
X1561625Y473966D03*
X1551875Y470586D03*
X1549925Y467206D03*
X1559675Y470586D03*
X1557725Y467206D03*
X1547975Y484106D03*
X1551875D03*
X1549925Y480726D03*
X1559675Y477346D03*
X1563575Y484106D03*
X1561625Y480726D03*
X1536275Y477346D03*
X1559675Y484106D03*
X1530425Y480726D03*
Y487486D03*
X1557725D03*
X1561625D03*
X1534325Y473966D03*
X1548300Y501500D03*
X1542475Y501900D03*
X1532539Y649378D03*
Y644278D03*
Y649178D03*
Y644278D03*
X1577000Y619500D03*
X1545407Y604713D03*
X1555600Y591100D03*
X1532539Y654278D03*
D03*
X1598602Y-600D03*
X1591848Y11406D03*
X1648748Y6325D03*
X1638865Y11105D03*
X1629148Y6825D03*
X1619798Y10755D03*
X1643865Y11105D03*
X1634148Y6825D03*
X1624798Y10755D03*
X1600898Y11355D03*
X1609833Y5425D03*
X1605898Y11355D03*
X1614833Y5425D03*
X1622635Y39900D03*
X1646848Y39462D03*
X1637398Y39862D03*
X1627715Y39934D03*
X1613741Y112341D03*
X1608056Y184771D03*
X1598878Y376346D03*
X1612250Y435500D03*
X1590580Y472370D03*
X1653748Y6325D03*
X1676428Y11381D03*
X1666979Y6236D03*
X1657369Y10258D03*
X1690948Y10725D03*
X1681428Y11381D03*
X1671979Y6236D03*
X1662373Y10154D03*
X1700200Y11317D03*
X1709771Y11261D03*
X1656298Y39462D03*
X1712308Y39350D03*
X1703073Y39679D03*
X1694098Y39462D03*
X1684648D03*
X1675198D03*
X1665748D03*
X1654685Y121790D03*
X1664135Y131239D03*
X1657835D03*
X1760693Y20045D03*
X1767069Y24010D03*
X1743152Y23197D03*
X1733168Y22312D03*
X1748152Y23197D03*
X1738168Y22312D03*
X1728678Y11381D03*
X1719297Y11180D03*
X1756895Y34252D03*
X1746550Y35925D03*
X1740598Y39486D03*
X1731183Y39465D03*
X1721758Y39880D03*
X1768886Y156173D03*
X1733484Y211631D03*
X1746125D03*
X1758725D03*
X1771325D03*
X1738484D03*
X1751125D03*
X1763725D03*
X1727193Y176525D03*
X1744792D03*
X1757390D03*
X1769988D03*
X1732193D03*
X1739792D03*
X1752390D03*
X1764988D03*
X1733563Y196776D03*
X1746082Y196843D03*
X1758668D03*
X1771241Y196841D03*
X1738563Y196776D03*
X1751082Y196843D03*
X1763668D03*
X1774451Y237712D03*
X1755554D03*
X1760554D03*
X1742398Y234681D03*
X1760767Y450408D03*
X1748169D03*
X1773366D03*
X1755767D03*
X1743169D03*
X1768366D03*
X1770325Y487355D03*
X1765325D03*
X1754300Y487855D03*
X1741900Y487755D03*
X1766700Y475655D03*
X1749300Y487855D03*
X1736900Y487755D03*
X1774300Y475055D03*
X1761700Y475655D03*
X1807127Y26918D03*
X1795078Y11900D03*
X1790078Y11860D03*
X1804462Y8830D03*
X1799462D03*
X1808100Y21800D03*
X1808363Y40033D03*
X1803300Y39900D03*
X1776325Y211631D03*
X1777587Y176525D03*
X1783925Y211631D03*
X1796526Y212231D03*
X1809125D03*
X1821685Y212161D03*
X1788925Y211631D03*
X1801526Y212231D03*
X1814125D03*
X1826685Y212161D03*
X1790185Y176525D03*
X1802784D03*
X1815382D03*
X1782587D03*
X1795185D03*
X1807784D03*
X1820382D03*
X1783841Y196841D03*
X1776241D03*
X1814041D03*
X1801441D03*
X1809041D03*
X1821682D03*
X1796441D03*
X1788841D03*
X1817282Y250498D03*
X1798384D03*
X1779451Y237712D03*
X1793384Y250498D03*
X1812282D03*
X1785964Y450408D03*
X1780964D03*
X1836495Y450600D03*
X1823760Y450408D03*
X1811161D03*
X1798563D03*
X1831495Y450600D03*
X1818760Y450408D03*
X1806161D03*
X1793563D03*
X1824125Y488930D03*
X1811975Y488730D03*
X1801125Y488930D03*
X1789525D03*
X1819125D03*
X1806975Y488730D03*
X1796125Y488930D03*
X1784525D03*
X1829967Y476927D03*
X1817375Y478320D03*
X1794975Y479300D03*
X1779300Y475055D03*
X1825297Y476927D03*
X1812375Y478320D03*
X1789975Y479300D03*
X1801525Y473955D03*
X1806525D03*
X1832500Y539500D03*
X1788300Y585100D03*
X1791349Y589122D03*
X1812452Y538501D03*
Y533601D03*
X1807852D03*
X1807752Y538501D03*
X1808152Y591601D03*
X1812852Y596401D03*
X1808252D03*
X1812852Y591601D03*
X1877103Y60791D03*
X1875100Y51300D03*
X1886400Y178700D03*
X1841630Y454321D03*
X1837000Y534900D03*
X1959300Y518000D03*
X1918880Y586460D03*
X1961715Y555639D03*
X1962500Y578500D03*
X1961771Y591744D03*
X1963300Y612800D03*
G54D161*
X1616849Y98738D03*
G54D162*
X1613069Y302692D03*
G54D225*
X1969883Y207007D03*
Y242441D03*
G54D117*
X1263600Y483540D03*
X1281600D03*
X1263600Y478420D03*
X1281600D03*
X1263600Y480980D03*
X1281600D03*
X1263600Y475860D03*
X1281600D03*
G54D42*
X28700Y484000D03*
Y480064D03*
X20600D03*
Y484000D03*
X28700Y482032D03*
Y478096D03*
X20600Y482032D03*
Y478096D03*
G54D153*
X1651250Y31059D03*
Y28500D03*
Y25941D03*
X1658750D03*
Y31059D03*
Y28500D03*
G54D51*
X89100Y124700D03*
X85350Y116200D03*
X81600Y124700D03*
X72750Y354750D03*
X80250D03*
X76500Y363250D03*
X1526900Y257200D03*
X1519400D03*
X1523150Y248700D03*
X1472781Y330195D03*
X1476531Y338695D03*
X1480281Y330195D03*
X1774250Y75500D03*
X1716000Y79500D03*
X1719750Y88000D03*
X1723500Y79500D03*
X1781750Y75500D03*
X1778000Y84000D03*
X1882250Y463250D03*
X1874750D03*
X1878500Y454750D03*
X1940000Y532600D03*
X1947500D03*
X1943750Y541100D03*
G54D60*
X94900Y332800D03*
X103900D03*
X94010Y343470D03*
X103010D03*
X1496800Y324500D03*
Y327060D03*
X1504200Y324500D03*
Y327060D03*
Y321940D03*
X1496800D03*
X1554500Y109940D03*
X1561900D03*
X1554500Y107380D03*
X1561900D03*
X1554500Y112500D03*
X1561900D03*
X1647500Y16500D03*
X1611900Y55500D03*
X1619300D03*
X1611900Y52940D03*
X1619300D03*
X1611900Y58060D03*
X1619300D03*
X1656500Y16500D03*
X1768628Y62395D03*
X1777628D03*
G54D171*
X1673296Y115832D03*
G54D24*
X15050Y30424D03*
X22050D03*
X22437Y66673D03*
X15437D03*
X22328Y73174D03*
X15328D03*
X22328Y79674D03*
X15328D03*
X15050Y37654D03*
X22050D03*
X15060Y44854D03*
X22060D03*
X4300Y242800D03*
X11300D03*
X-11190Y454200D03*
X-4190D03*
X12300Y584000D03*
X5300D03*
X12300Y577500D03*
X5300D03*
X12300Y555500D03*
X5300D03*
X12300Y549000D03*
X5300D03*
X12300Y542500D03*
X5300D03*
X12300Y590500D03*
X5300D03*
X103600Y31978D03*
Y-8400D03*
Y69778D03*
X61000Y216102D03*
X54000D03*
X110600Y31978D03*
Y-8400D03*
Y69778D03*
X136263Y261516D03*
X129263D03*
X136263Y268116D03*
X129263D03*
X136263Y255016D03*
X129263D03*
X136263Y229516D03*
X129263D03*
X136263Y236116D03*
X129263D03*
X136263Y223016D03*
X129263D03*
X136263Y287016D03*
X129263D03*
X136263Y293516D03*
X129263D03*
X136263Y300116D03*
X129263D03*
X136263Y332116D03*
X129263D03*
X136263Y325516D03*
X129263D03*
X136263Y319016D03*
X129263D03*
X136263Y364116D03*
X129263D03*
X136263Y357516D03*
X129263D03*
X136263Y351016D03*
X129263D03*
X136263Y396116D03*
X129263D03*
X136263Y383016D03*
X129263D03*
X136263Y389516D03*
X129263D03*
X378292Y13078D03*
X371292D03*
X379692Y31978D03*
X372692D03*
X408892Y-15000D03*
X401892D03*
X415892D03*
X372592Y-5810D03*
X379592D03*
X378892Y69100D03*
X371892D03*
X378312Y51178D03*
X371312D03*
X375492Y106500D03*
X382492D03*
X384448Y272041D03*
X391448D03*
X389956Y329710D03*
X382956D03*
X378120Y551360D03*
X371120D03*
X378262Y532978D03*
X371262D03*
X377340Y589650D03*
X370340D03*
X378232Y570818D03*
X371232D03*
X413324Y617756D03*
X399824D03*
X406824D03*
X379760Y618220D03*
X372760D03*
X360706Y618127D03*
X367706D03*
X436392Y-15000D03*
X429392D03*
X422892D03*
X446392Y107500D03*
X439392D03*
X440148Y274841D03*
X447148D03*
X448250Y496390D03*
X441250D03*
X427324Y617756D03*
X434324D03*
X420324D03*
X664500Y60000D03*
X657500D03*
X664500Y52000D03*
X657500D03*
X725230Y-10380D03*
X718230D03*
X721130Y42955D03*
X696000Y203000D03*
X703000D03*
X696000Y216500D03*
X703000D03*
X696000Y209500D03*
X703000D03*
X688700Y313000D03*
X695700D03*
X721900Y529700D03*
X753208Y31978D03*
X760208D03*
X753208Y-8400D03*
X760208D03*
X753208Y69778D03*
X760208D03*
X728130Y42955D03*
X785932Y261133D03*
X778932D03*
X785932Y254633D03*
X778932D03*
X785932Y236533D03*
X778932D03*
X785932Y230033D03*
X778932D03*
X786000Y223300D03*
X779000D03*
X785932Y267633D03*
X778932D03*
X785932Y299833D03*
X778932D03*
X785932Y286833D03*
X778932D03*
X785932Y293333D03*
X778932D03*
X785932Y319653D03*
X778932D03*
X785932Y326153D03*
X778932D03*
X786332Y332653D03*
X779332D03*
X786000Y383000D03*
X779000D03*
X785932Y357633D03*
X778932D03*
X785932Y364133D03*
X778932D03*
X785932Y351133D03*
X778932D03*
X786000Y389500D03*
X779000D03*
X786000Y396000D03*
X779000D03*
X728900Y529700D03*
X1029300Y31978D03*
X1022300D03*
X1029400Y13078D03*
X1022400D03*
X1023621Y-15762D03*
X1030621D03*
X1028600Y51400D03*
X1021600D03*
X1029300Y69100D03*
X1022300D03*
X1031200Y104500D03*
X1034056Y272041D03*
X1032564Y329710D03*
X1028800Y532978D03*
X1021800D03*
X1028900Y551500D03*
X1021900D03*
X1028300Y570778D03*
X1021300D03*
X1027070Y589650D03*
X1020070D03*
X1030700Y618200D03*
X1023700D03*
X1011234Y618177D03*
X1018234D03*
X1058500Y-15000D03*
X1051500D03*
X1072500D03*
X1065500D03*
X1086000D03*
X1079000D03*
X1096000Y105781D03*
X1089000D03*
X1038200Y104500D03*
X1089756Y274841D03*
X1096756D03*
X1041056Y272041D03*
X1039564Y329710D03*
X1041800Y496200D03*
X1048800D03*
X1095532Y617956D03*
X1088532D03*
X1068032D03*
X1061032D03*
X1081532D03*
X1074532D03*
X1320700Y111450D03*
X1313700D03*
X1320700Y119450D03*
X1313700D03*
X1360989Y-4107D03*
X1367989D03*
X1360989Y-10607D03*
X1367989D03*
X1360989Y-17207D03*
X1367989D03*
X1361400Y15200D03*
X1368400D03*
X1361400Y21700D03*
X1368400D03*
X1361400Y28200D03*
X1368400D03*
X1390531Y90354D03*
X1383531D03*
X1390531Y104354D03*
X1383531D03*
X1363700Y373500D03*
X1370700D03*
X1363800Y380200D03*
X1370800D03*
X1363700Y386700D03*
X1370700D03*
X1365500Y576156D03*
X1372500D03*
X1365500Y569156D03*
X1372500D03*
X1365500Y562656D03*
X1372500D03*
X1365400Y605800D03*
X1372400D03*
X1365100Y598576D03*
X1372100D03*
X1365100Y592076D03*
X1372100D03*
X1585270Y558204D03*
Y565204D03*
X1635876Y190731D03*
X1628876D03*
X1592270Y558204D03*
Y565204D03*
X1770600Y46800D03*
X1766600Y37800D03*
X1774600D03*
X1837000Y48500D03*
X1830000D03*
X1817772Y47218D03*
X1824772D03*
X1829800Y492500D03*
X1836800D03*
X1829800Y486000D03*
X1836800D03*
X1928000Y440730D03*
X1921000D03*
X1908000D03*
X1915000D03*
G54D216*
X1906500Y214650D03*
Y223650D03*
G54D180*
X1741189Y165669D03*
X1745689D03*
X1750189D03*
X1736689D03*
X1732189D03*
X1727689D03*
X1723189D03*
X1718689D03*
X1723189Y173125D03*
X1718689D03*
X1727689D03*
X1732189D03*
X1736689D03*
X1741189D03*
X1745689D03*
X1750189D03*
X1721808Y601405D03*
X1781800Y588450D03*
G54D207*
X1851250Y561000D03*
G54D126*
X1442000Y-15000D03*
X1505000D03*
X1703503D03*
X1769504D03*
G54D108*
X1223453Y336318D03*
G54D135*
X1466693Y375787D03*
X1572599Y505315D03*
X1627642Y-14488D03*
X1647327Y-315D03*
G54D144*
X1527844Y159531D03*
G54D15*
X-14488Y434094D03*
X-4488D03*
X5512D03*
X15512D03*
X89980Y145531D03*
X99980D03*
X109980D03*
X119980D03*
G54D33*
X3937Y204370D03*
X-3937D03*
X-11811D03*
X35433D03*
X27559D03*
X19685D03*
X3937Y227992D03*
X-3937D03*
X-11811D03*
X35433D03*
X27559D03*
X19685D03*
X3937Y313504D03*
X-3937D03*
X-11811D03*
X3937Y337126D03*
X-3937D03*
X-11811D03*
X35433D03*
X27559D03*
X19685D03*
X35433Y313504D03*
X27559D03*
X19685D03*
X1527844Y80791D03*
G54D226*
G01X548049Y-193422D02*
Y-210922D01*
G01X543027Y-193422D02*
X553071D01*
G01X565549Y-199256D02*
Y-210922D01*
G01Y-194589D02*
X565112Y-194297D01*
Y-193714D01*
X565549Y-193422D01*
X565986Y-193714D01*
Y-194297D01*
X565549Y-194589D01*
G01X583049Y-210922D02*
X581739Y-210630D01*
X580429Y-209464D01*
X579555Y-207422D01*
X579119Y-205089D01*
X579555Y-202755D01*
X580429Y-200714D01*
X581739Y-199547D01*
X583049Y-199256D01*
X584359Y-199547D01*
X585669Y-200714D01*
X586542Y-202755D01*
X586761Y-205089D01*
X586542Y-207422D01*
X585669Y-209464D01*
X584359Y-210630D01*
X583049Y-210922D01*
G01X597492Y-215297D02*
X599021Y-216464D01*
X600767Y-216755D01*
X602295Y-216464D01*
X603606Y-215006D01*
X604479Y-212964D01*
Y-199256D01*
G01Y-201589D02*
X603606Y-200422D01*
X602295Y-199547D01*
X600767Y-199256D01*
X599021Y-199839D01*
X597929Y-201005D01*
X597055Y-203047D01*
X596619Y-205089D01*
X596837Y-206839D01*
X597711Y-208881D01*
X599021Y-210339D01*
X600767Y-210922D01*
X602077Y-210630D01*
X603606Y-209464D01*
X604479Y-208298D01*
G01X621979Y-210922D02*
Y-199256D01*
G01Y-201297D02*
X621106Y-200131D01*
X619795Y-199547D01*
X618267Y-199256D01*
X616739Y-199839D01*
X615429Y-201005D01*
X614555Y-202755D01*
X614119Y-205089D01*
X614555Y-207422D01*
X615429Y-209172D01*
X616739Y-210339D01*
X618267Y-210922D01*
X619795Y-210630D01*
X621106Y-209756D01*
X621979Y-208589D01*
G01X648682Y-210922D02*
Y-193422D01*
X653922D01*
X655669Y-194297D01*
X656979Y-196339D01*
X657416Y-198672D01*
X656979Y-201005D01*
X655887Y-202755D01*
X653922Y-203631D01*
X648682D01*
G01X674479Y-210922D02*
Y-199256D01*
G01Y-201297D02*
X673606Y-200131D01*
X672295Y-199547D01*
X670767Y-199256D01*
X669239Y-199839D01*
X667929Y-201005D01*
X667055Y-202755D01*
X666619Y-205089D01*
X667055Y-207422D01*
X667929Y-209172D01*
X669239Y-210339D01*
X670767Y-210922D01*
X672295Y-210630D01*
X673606Y-209756D01*
X674479Y-208589D01*
G01X684774Y-208881D02*
X685866Y-210047D01*
X687394Y-210922D01*
X688704D01*
X690014Y-210339D01*
X690887Y-209464D01*
X691324Y-208298D01*
X691106Y-206547D01*
X690232Y-205672D01*
X686302Y-203922D01*
X685429Y-201880D01*
X685866Y-200422D01*
X686739Y-199547D01*
X688049Y-199256D01*
X689359Y-199547D01*
X690669Y-200422D01*
G01X702274Y-208881D02*
X703366Y-210047D01*
X704894Y-210922D01*
X706204D01*
X707514Y-210339D01*
X708387Y-209464D01*
X708824Y-208298D01*
X708606Y-206547D01*
X707732Y-205672D01*
X703802Y-203922D01*
X702929Y-201880D01*
X703366Y-200422D01*
X704239Y-199547D01*
X705549Y-199256D01*
X706859Y-199547D01*
X708169Y-200422D01*
G01X735746Y-210922D02*
Y-193422D01*
X740112D01*
X741859Y-194297D01*
X743169Y-195464D01*
X744261Y-197213D01*
X745134Y-199256D01*
X745352Y-202172D01*
X745134Y-205089D01*
X744261Y-207131D01*
X743169Y-208881D01*
X741859Y-210047D01*
X740112Y-210922D01*
X735746D01*
G01X752590Y-193422D02*
X758049Y-210922D01*
X763508Y-193422D01*
G01X775549D02*
Y-210922D01*
G01X770527Y-193422D02*
X780571D01*
G01X804872Y-210922D02*
Y-193422D01*
X810549Y-208005D01*
X816226Y-193422D01*
Y-210922D01*
G01X829795Y-201589D02*
X830669Y-200714D01*
X831324Y-199256D01*
X831761Y-197213D01*
X831324Y-195464D01*
X830451Y-194297D01*
X828922Y-193422D01*
X823027D01*
Y-210922D01*
X830232D01*
X831761Y-209756D01*
X832634Y-208005D01*
X833071Y-205964D01*
X832634Y-203922D01*
X831324Y-202172D01*
X829795Y-201589D01*
X823027D01*
G01X647372Y-165922D02*
Y-148422D01*
X653049Y-163005D01*
X658726Y-148422D01*
Y-165922D01*
G01X670549D02*
X669239Y-165630D01*
X667929Y-164464D01*
X667055Y-162422D01*
X666619Y-160089D01*
X667055Y-157755D01*
X667929Y-155714D01*
X669239Y-154547D01*
X670549Y-154256D01*
X671859Y-154547D01*
X673169Y-155714D01*
X674042Y-157755D01*
X674261Y-160089D01*
X674042Y-162422D01*
X673169Y-164464D01*
X671859Y-165630D01*
X670549Y-165922D01*
G01X691979Y-148422D02*
Y-165922D01*
G01Y-163298D02*
X691106Y-164756D01*
X689795Y-165630D01*
X688267Y-165922D01*
X686521Y-165339D01*
X685211Y-163881D01*
X684337Y-162131D01*
X684119Y-160089D01*
X684337Y-158047D01*
X685211Y-156297D01*
X686521Y-154839D01*
X688267Y-154256D01*
X689795Y-154547D01*
X690887Y-155131D01*
X691979Y-156297D01*
G01X702274Y-158047D02*
X709261D01*
X708606Y-156005D01*
X707514Y-154839D01*
X705986Y-154256D01*
X704457Y-154547D01*
X703147Y-155422D01*
X702274Y-157464D01*
X701837Y-159214D01*
Y-160964D01*
X702274Y-162714D01*
X703366Y-164464D01*
X704676Y-165630D01*
X706204Y-165922D01*
X707732Y-165339D01*
X709261Y-163589D01*
G01X723049Y-165922D02*
Y-148422D01*
G01X975549Y-210922D02*
Y-193422D01*
X972929Y-196922D01*
G01Y-210922D02*
X978169D01*
G01X988246Y-208298D02*
X989555Y-209756D01*
X991084Y-210630D01*
X993049Y-210922D01*
X995014Y-210339D01*
X996542Y-209172D01*
X997634Y-207131D01*
X997852Y-204797D01*
X997416Y-202464D01*
X996324Y-201005D01*
X994795Y-199839D01*
X993267Y-199547D01*
X991739Y-199839D01*
X989774Y-201005D01*
X990429Y-193422D01*
X996324D01*
G01X1010549Y-210922D02*
Y-193422D01*
X1007929Y-196922D01*
G01Y-210922D02*
X1013169D01*
G01X1023901Y-196339D02*
X1025211Y-194589D01*
X1026739Y-193714D01*
X1028486Y-193422D01*
X1030669Y-194005D01*
X1032197Y-195464D01*
X1032634Y-197213D01*
X1032416Y-198964D01*
X1031542Y-200422D01*
X1027176Y-203339D01*
X1025211Y-205380D01*
X1023901Y-208298D01*
X1023464Y-210922D01*
X1032634D01*
G01X1041401Y-203631D02*
X1042929Y-201589D01*
X1044239Y-200422D01*
X1045986Y-199839D01*
X1047514Y-200422D01*
X1048606Y-201589D01*
X1049479Y-203339D01*
X1049697Y-205380D01*
X1049479Y-207131D01*
X1048606Y-208881D01*
X1047295Y-210339D01*
X1045767Y-210922D01*
X1044021Y-210339D01*
X1042492Y-208589D01*
X1041619Y-205964D01*
X1041401Y-203047D01*
X1041837Y-199256D01*
X1042492Y-197213D01*
X1043584Y-195172D01*
X1045112Y-193714D01*
X1046641Y-193422D01*
X1048169Y-194005D01*
X1049261Y-195464D01*
G01X962432Y-165922D02*
Y-148422D01*
X967672D01*
X969419Y-149297D01*
X970729Y-151339D01*
X971166Y-153672D01*
X970729Y-156005D01*
X969637Y-157755D01*
X967672Y-158631D01*
X962432D01*
G01X989102Y-149881D02*
X987792Y-149005D01*
X986264Y-148422D01*
X984517D01*
X982552Y-149297D01*
X981024Y-150755D01*
X979932Y-152506D01*
X979059Y-155422D01*
X978840Y-158047D01*
X979277Y-160672D01*
X979932Y-162422D01*
X981242Y-164172D01*
X982771Y-165339D01*
X984299Y-165922D01*
X985827D01*
X987356Y-165339D01*
X988666Y-164464D01*
X989758Y-163298D01*
G01X1003545Y-156589D02*
X1004419Y-155714D01*
X1005074Y-154256D01*
X1005511Y-152213D01*
X1005074Y-150464D01*
X1004201Y-149297D01*
X1002672Y-148422D01*
X996777D01*
Y-165922D01*
X1003982D01*
X1005511Y-164756D01*
X1006384Y-163005D01*
X1006821Y-160964D01*
X1006384Y-158922D01*
X1005074Y-157172D01*
X1003545Y-156589D01*
X996777D01*
G01X1012749Y-171755D02*
X1025849D01*
G01X1031777Y-165922D02*
Y-148422D01*
X1041821Y-165922D01*
Y-148422D01*
G01X1054299Y-165922D02*
X1052552Y-165630D01*
X1051024Y-164464D01*
X1049714Y-162714D01*
X1048840Y-160672D01*
X1048404Y-158339D01*
Y-156005D01*
X1048840Y-153672D01*
X1049714Y-151630D01*
X1051024Y-149881D01*
X1052552Y-148714D01*
X1054299Y-148422D01*
X1056045Y-148714D01*
X1057574Y-149881D01*
X1058884Y-151630D01*
X1059758Y-153672D01*
X1060194Y-156005D01*
Y-158339D01*
X1059758Y-160672D01*
X1058884Y-162714D01*
X1057574Y-164464D01*
X1056045Y-165630D01*
X1054299Y-165922D01*
G01X1128099Y-210922D02*
Y-193422D01*
X1125479Y-196922D01*
G01Y-210922D02*
X1130719D01*
G01X1147345Y-201589D02*
X1148219Y-200714D01*
X1148874Y-199256D01*
X1149311Y-197213D01*
X1148874Y-195464D01*
X1148001Y-194297D01*
X1146472Y-193422D01*
X1140577D01*
Y-210922D01*
X1147782D01*
X1149311Y-209756D01*
X1150184Y-208005D01*
X1150621Y-205964D01*
X1150184Y-203922D01*
X1148874Y-202172D01*
X1147345Y-201589D01*
X1140577D01*
G01X1105140Y-148422D02*
X1110599Y-165922D01*
X1116058Y-148422D01*
G01X1132466Y-165922D02*
X1123732D01*
Y-148422D01*
X1132466D01*
G01X1128972Y-156880D02*
X1123732D01*
G01X1141232Y-165922D02*
Y-148422D01*
X1146691D01*
X1148437Y-149297D01*
X1149529Y-150464D01*
X1149966Y-152797D01*
X1149529Y-155131D01*
X1148219Y-156589D01*
X1146691Y-157464D01*
X1141232D01*
G01X1146691D02*
X1149966Y-165922D01*
G01X1163099Y-166505D02*
X1162662Y-166214D01*
Y-165630D01*
X1163099Y-165339D01*
X1163536Y-165630D01*
Y-166214D01*
X1163099Y-166505D01*
G01X1311303Y-201589D02*
X1310429Y-200714D01*
X1309774Y-199256D01*
X1309337Y-197213D01*
X1309774Y-195464D01*
X1310647Y-194297D01*
X1312176Y-193422D01*
X1318071D01*
Y-210922D01*
X1310866D01*
X1309337Y-209756D01*
X1308464Y-208005D01*
X1308027Y-205964D01*
X1308464Y-203922D01*
X1309774Y-202172D01*
X1311303Y-201589D01*
X1318071D01*
G01X1301226Y-210922D02*
Y-193422D01*
X1295549Y-208005D01*
X1289872Y-193422D01*
Y-210922D01*
G01X1283508D02*
X1278049Y-193422D01*
X1272590Y-210922D01*
G01X1274556Y-204797D02*
X1281543D01*
G01X1265134Y-208589D02*
X1263387Y-210047D01*
X1261422Y-210922D01*
X1259676D01*
X1257929Y-210047D01*
X1256619Y-208589D01*
X1255964Y-206547D01*
X1256401Y-204506D01*
X1257492Y-202755D01*
X1259457Y-201589D01*
X1262077Y-201005D01*
X1263606Y-199839D01*
X1264261Y-197797D01*
X1263824Y-195755D01*
X1262732Y-194297D01*
X1261204Y-193422D01*
X1259676D01*
X1258147Y-194005D01*
X1256837Y-195464D01*
G01X1247852Y-210922D02*
Y-193422D01*
G01X1239556D02*
X1247852Y-204214D01*
G01X1238246Y-210922D02*
X1244141Y-199256D01*
G01X1238682Y-148422D02*
Y-165922D01*
X1247416D01*
G01X1264479D02*
Y-154256D01*
G01Y-156297D02*
X1263606Y-155131D01*
X1262295Y-154547D01*
X1260767Y-154256D01*
X1259239Y-154839D01*
X1257929Y-156005D01*
X1257055Y-157755D01*
X1256619Y-160089D01*
X1257055Y-162422D01*
X1257929Y-164172D01*
X1259239Y-165339D01*
X1260767Y-165922D01*
X1262295Y-165630D01*
X1263606Y-164756D01*
X1264479Y-163589D01*
G01X1273464Y-171172D02*
X1274774Y-171755D01*
X1276521Y-171172D01*
X1277612Y-170006D01*
X1278486Y-168547D01*
X1279795Y-163881D01*
X1282634Y-154256D01*
G01X1275647D02*
X1279795Y-163881D01*
G01X1292274Y-158047D02*
X1299261D01*
X1298606Y-156005D01*
X1297514Y-154839D01*
X1295986Y-154256D01*
X1294457Y-154547D01*
X1293147Y-155422D01*
X1292274Y-157464D01*
X1291837Y-159214D01*
Y-160964D01*
X1292274Y-162714D01*
X1293366Y-164464D01*
X1294676Y-165630D01*
X1296204Y-165922D01*
X1297732Y-165339D01*
X1299261Y-163589D01*
G01X1309992Y-165922D02*
Y-154256D01*
G01Y-156589D02*
X1311084Y-155422D01*
X1312176Y-154547D01*
X1313704Y-154256D01*
X1314795Y-154547D01*
X1316106Y-155422D01*
G01X1380796Y-165922D02*
Y-148422D01*
X1385162D01*
X1386909Y-149297D01*
X1388219Y-150464D01*
X1389311Y-152213D01*
X1390184Y-154256D01*
X1390402Y-157172D01*
X1390184Y-160089D01*
X1389311Y-162131D01*
X1388219Y-163881D01*
X1386909Y-165047D01*
X1385162Y-165922D01*
X1380796D01*
G01X1399824Y-158047D02*
X1406811D01*
X1406156Y-156005D01*
X1405064Y-154839D01*
X1403536Y-154256D01*
X1402007Y-154547D01*
X1400697Y-155422D01*
X1399824Y-157464D01*
X1399387Y-159214D01*
Y-160964D01*
X1399824Y-162714D01*
X1400916Y-164464D01*
X1402226Y-165630D01*
X1403754Y-165922D01*
X1405282Y-165339D01*
X1406811Y-163589D01*
G01X1417324Y-163881D02*
X1418416Y-165047D01*
X1419944Y-165922D01*
X1421254D01*
X1422564Y-165339D01*
X1423437Y-164464D01*
X1423874Y-163298D01*
X1423656Y-161547D01*
X1422782Y-160672D01*
X1418852Y-158922D01*
X1417979Y-156880D01*
X1418416Y-155422D01*
X1419289Y-154547D01*
X1420599Y-154256D01*
X1421909Y-154547D01*
X1423219Y-155422D01*
G01X1438099Y-154256D02*
Y-165922D01*
G01Y-149589D02*
X1437662Y-149297D01*
Y-148714D01*
X1438099Y-148422D01*
X1438536Y-148714D01*
Y-149297D01*
X1438099Y-149589D01*
G01X1452542Y-170297D02*
X1454071Y-171464D01*
X1455817Y-171755D01*
X1457345Y-171464D01*
X1458656Y-170006D01*
X1459529Y-167964D01*
Y-154256D01*
G01Y-156589D02*
X1458656Y-155422D01*
X1457345Y-154547D01*
X1455817Y-154256D01*
X1454071Y-154839D01*
X1452979Y-156005D01*
X1452105Y-158047D01*
X1451669Y-160089D01*
X1451887Y-161839D01*
X1452761Y-163881D01*
X1454071Y-165339D01*
X1455817Y-165922D01*
X1457127Y-165630D01*
X1458656Y-164464D01*
X1459529Y-163298D01*
G01X1469387Y-165922D02*
Y-154256D01*
G01Y-157172D02*
X1470261Y-155714D01*
X1471571Y-154547D01*
X1473317Y-154256D01*
X1474845Y-154547D01*
X1476156Y-155714D01*
X1476811Y-157755D01*
Y-165922D01*
G01X1487324Y-158047D02*
X1494311D01*
X1493656Y-156005D01*
X1492564Y-154839D01*
X1491036Y-154256D01*
X1489507Y-154547D01*
X1488197Y-155422D01*
X1487324Y-157464D01*
X1486887Y-159214D01*
Y-160964D01*
X1487324Y-162714D01*
X1488416Y-164464D01*
X1489726Y-165630D01*
X1491254Y-165922D01*
X1492782Y-165339D01*
X1494311Y-163589D01*
G01X1505042Y-165922D02*
Y-154256D01*
G01Y-156589D02*
X1506134Y-155422D01*
X1507226Y-154547D01*
X1508754Y-154256D01*
X1509845Y-154547D01*
X1511156Y-155422D01*
G01X1426729Y-193422D02*
X1431969D01*
G01X1429349D02*
Y-210922D01*
G01X1426729D02*
X1431969D01*
G01X1441390Y-193422D02*
X1446849Y-210922D01*
X1452308Y-193422D01*
G01X1464349Y-210922D02*
Y-203047D01*
X1459982Y-193422D01*
G01X1468716D02*
X1464349Y-203047D01*
G01X1551799Y-193422D02*
X1550052Y-194005D01*
X1548742Y-195464D01*
X1547869Y-197213D01*
X1547214Y-199547D01*
X1546996Y-202172D01*
X1547214Y-204797D01*
X1547869Y-207131D01*
X1548742Y-208881D01*
X1550052Y-210339D01*
X1551799Y-210922D01*
X1553545Y-210339D01*
X1554856Y-208881D01*
X1555729Y-207131D01*
X1556384Y-204797D01*
X1556602Y-202172D01*
X1556384Y-199547D01*
X1555729Y-197213D01*
X1554856Y-195464D01*
X1553545Y-194005D01*
X1551799Y-193422D01*
G01X1565151Y-196339D02*
X1566461Y-194589D01*
X1567989Y-193714D01*
X1569736Y-193422D01*
X1571919Y-194005D01*
X1573447Y-195464D01*
X1573884Y-197213D01*
X1573666Y-198964D01*
X1572792Y-200422D01*
X1568426Y-203339D01*
X1566461Y-205380D01*
X1565151Y-208298D01*
X1564714Y-210922D01*
X1573884D01*
G01X1582869Y-211505D02*
X1590729Y-193422D01*
G01X1604299Y-210922D02*
Y-193422D01*
X1601679Y-196922D01*
G01Y-210922D02*
X1606919D01*
G01X1621799Y-193422D02*
X1620052Y-194005D01*
X1618742Y-195464D01*
X1617869Y-197213D01*
X1617214Y-199547D01*
X1616996Y-202172D01*
X1617214Y-204797D01*
X1617869Y-207131D01*
X1618742Y-208881D01*
X1620052Y-210339D01*
X1621799Y-210922D01*
X1623545Y-210339D01*
X1624856Y-208881D01*
X1625729Y-207131D01*
X1626384Y-204797D01*
X1626602Y-202172D01*
X1626384Y-199547D01*
X1625729Y-197213D01*
X1624856Y-195464D01*
X1623545Y-194005D01*
X1621799Y-193422D01*
G01X1635369Y-211505D02*
X1643229Y-193422D01*
G01X1652651Y-196339D02*
X1653961Y-194589D01*
X1655489Y-193714D01*
X1657236Y-193422D01*
X1659419Y-194005D01*
X1660947Y-195464D01*
X1661384Y-197213D01*
X1661166Y-198964D01*
X1660292Y-200422D01*
X1655926Y-203339D01*
X1653961Y-205380D01*
X1652651Y-208298D01*
X1652214Y-210922D01*
X1661384D01*
G01X1674299Y-193422D02*
X1672552Y-194005D01*
X1671242Y-195464D01*
X1670369Y-197213D01*
X1669714Y-199547D01*
X1669496Y-202172D01*
X1669714Y-204797D01*
X1670369Y-207131D01*
X1671242Y-208881D01*
X1672552Y-210339D01*
X1674299Y-210922D01*
X1676045Y-210339D01*
X1677356Y-208881D01*
X1678229Y-207131D01*
X1678884Y-204797D01*
X1679102Y-202172D01*
X1678884Y-199547D01*
X1678229Y-197213D01*
X1677356Y-195464D01*
X1676045Y-194005D01*
X1674299Y-193422D01*
G01X1691799Y-210922D02*
Y-193422D01*
X1689179Y-196922D01*
G01Y-210922D02*
X1694419D01*
G01X1708862D02*
X1709299Y-207131D01*
X1709954Y-203922D01*
X1710827Y-201005D01*
X1711919Y-197797D01*
X1713666Y-193422D01*
X1704932D01*
G01X1599496Y-165922D02*
Y-148422D01*
X1603862D01*
X1605609Y-149297D01*
X1606919Y-150464D01*
X1608011Y-152213D01*
X1608884Y-154256D01*
X1609102Y-157172D01*
X1608884Y-160089D01*
X1608011Y-162131D01*
X1606919Y-163881D01*
X1605609Y-165047D01*
X1603862Y-165922D01*
X1599496D01*
G01X1625729D02*
Y-154256D01*
G01Y-156297D02*
X1624856Y-155131D01*
X1623545Y-154547D01*
X1622017Y-154256D01*
X1620489Y-154839D01*
X1619179Y-156005D01*
X1618305Y-157755D01*
X1617869Y-160089D01*
X1618305Y-162422D01*
X1619179Y-164172D01*
X1620489Y-165339D01*
X1622017Y-165922D01*
X1623545Y-165630D01*
X1624856Y-164756D01*
X1625729Y-163589D01*
G01X1639299Y-148422D02*
Y-165922D01*
G01X1636242Y-154256D02*
X1642356D01*
G01X1653524Y-158047D02*
X1660511D01*
X1659856Y-156005D01*
X1658764Y-154839D01*
X1657236Y-154256D01*
X1655707Y-154547D01*
X1654397Y-155422D01*
X1653524Y-157464D01*
X1653087Y-159214D01*
Y-160964D01*
X1653524Y-162714D01*
X1654616Y-164464D01*
X1655926Y-165630D01*
X1657454Y-165922D01*
X1658982Y-165339D01*
X1660511Y-163589D01*
G54D43*
X44100Y507100D03*
X1468500Y176700D03*
X1596130Y205480D03*
X1623800Y169500D03*
X1666300Y85000D03*
X1742200Y87950D03*
X1755708Y132250D03*
Y127750D03*
Y141250D03*
Y136750D03*
X1764270Y132250D03*
Y127750D03*
Y141250D03*
Y136750D03*
X1755708Y145798D03*
X1764222D03*
X1721900Y198700D03*
X1888500Y225100D03*
G54D208*
X1952756Y-14960D03*
Y58268D03*
G54D163*
X1595943Y441200D03*
Y447800D03*
G54D190*
X1780700Y89500D03*
Y94500D03*
X1802300D03*
Y89500D03*
X1780700Y99500D03*
X1802300D03*
Y104500D03*
X1780700D03*
G54D217*
X1952250Y240355D03*
G54D61*
X84781Y327900D03*
X86750Y332500D03*
X82813Y327900D03*
Y332500D03*
X84781D03*
X100431Y312900D03*
X102400Y317500D03*
X98463Y312900D03*
Y317500D03*
X100431D03*
X1613999Y23700D03*
X1615968Y28300D03*
X1612031Y23700D03*
Y28300D03*
X1613999D03*
G54D118*
X1296679Y228017D03*
X1289679Y222899D03*
X1296679Y225458D03*
X1289679Y228017D03*
X1296679Y222899D03*
X1460354Y148569D03*
Y146010D03*
Y151128D03*
X1524200Y12218D03*
Y7100D03*
X1510200Y9641D03*
Y12200D03*
Y7082D03*
X1517200D03*
Y9641D03*
Y12200D03*
X1480354Y151039D03*
Y148479D03*
X1473354Y151039D03*
Y145919D03*
Y148479D03*
X1480354Y145919D03*
X1467354Y151128D03*
Y146010D03*
X1528065Y171552D03*
Y174112D03*
Y176672D03*
X1506000Y186570D03*
Y184010D03*
X1499000Y186570D03*
Y181450D03*
Y184010D03*
X1506000Y181450D03*
X1488962Y190185D03*
X1481962Y187626D03*
Y185067D03*
X1488962D03*
X1481962Y190185D03*
X1531200Y7100D03*
Y9659D03*
Y12218D03*
X1535065Y171552D03*
Y176672D03*
Y174112D03*
X1548628Y176772D03*
Y174212D03*
X1541628Y176772D03*
Y171652D03*
Y174212D03*
X1548628Y171652D03*
X1547650Y258590D03*
X1540650Y256031D03*
Y253472D03*
X1547650D03*
X1540650Y258590D03*
X1544300Y248318D03*
X1537300Y245759D03*
Y243200D03*
X1544300D03*
X1537300Y248318D03*
X1594600Y-14300D03*
X1601600Y-11741D03*
X1594600Y-9182D03*
X1601600Y-14300D03*
Y-9182D03*
X1613000Y-6218D03*
X1620000Y-3659D03*
X1613000Y-1100D03*
X1620000Y-6218D03*
Y-1100D03*
X1648296Y301559D03*
X1641296Y296441D03*
Y299000D03*
X1648296Y296441D03*
X1641296Y301559D03*
X1620717Y370711D03*
Y368151D03*
X1613717Y370711D03*
Y365591D03*
Y368151D03*
X1620717Y365591D03*
Y349711D03*
Y347151D03*
X1613717Y349711D03*
Y344591D03*
Y347151D03*
X1620717Y344591D03*
Y360211D03*
Y357651D03*
X1613717Y360211D03*
Y355091D03*
Y357651D03*
X1620717Y355091D03*
X1662526Y300586D03*
X1655526Y298027D03*
X1662526Y295468D03*
X1655526Y300586D03*
Y295468D03*
X1759900Y509359D03*
Y506800D03*
X1752900Y509359D03*
Y506800D03*
Y511918D03*
X1759900D03*
X1757792Y581471D03*
X1750792Y578912D03*
X1757792Y576353D03*
X1750792Y581471D03*
Y576353D03*
X1761300Y613600D03*
Y618718D03*
X1754300D03*
Y616159D03*
Y613600D03*
X1735000Y618700D03*
Y613582D03*
X1742000D03*
Y616141D03*
Y618700D03*
X1808400Y557982D03*
X1815400Y560541D03*
X1808400Y563100D03*
X1815400Y557982D03*
Y563100D03*
X1872115Y586119D03*
X1879115D03*
X1872115Y588679D03*
X1879115Y591239D03*
Y588679D03*
X1872115Y591239D03*
G54D70*
X57745Y483757D03*
Y490757D03*
X412501Y275410D03*
Y268410D03*
X398048Y275441D03*
Y268441D03*
X405301Y275410D03*
Y268410D03*
X411001Y327910D03*
Y334910D03*
X418201Y327910D03*
Y334910D03*
X413001Y320410D03*
Y313410D03*
X377648Y315841D03*
Y322841D03*
X396348Y327941D03*
Y334941D03*
X403748Y327941D03*
Y334941D03*
X391401Y320410D03*
Y313410D03*
X384201Y320410D03*
Y313410D03*
X398601Y320410D03*
Y313410D03*
X405801Y320410D03*
Y313410D03*
X411501Y299410D03*
Y306410D03*
Y282410D03*
Y289410D03*
X382701Y282410D03*
Y289410D03*
X375501Y282410D03*
Y289410D03*
X368301Y282410D03*
Y289410D03*
X382701Y299410D03*
Y306410D03*
X389901Y282410D03*
Y289410D03*
Y299410D03*
Y306410D03*
X375501Y299410D03*
Y306410D03*
X368301Y299410D03*
Y306410D03*
X404301Y299410D03*
Y306410D03*
Y282410D03*
Y289410D03*
X397101Y299410D03*
Y306410D03*
Y282410D03*
Y289410D03*
X371148Y315841D03*
Y322841D03*
X434101Y275410D03*
Y268410D03*
X419701Y275410D03*
Y268410D03*
X426901Y275410D03*
Y268410D03*
X425401Y327910D03*
Y334910D03*
X432601Y327910D03*
Y334910D03*
X455648Y322341D03*
Y315341D03*
X420201Y320410D03*
Y313410D03*
X441801Y320291D03*
Y313291D03*
X434601Y320410D03*
Y313410D03*
X449001Y320410D03*
Y313410D03*
X427401Y320410D03*
Y313410D03*
X447648Y289341D03*
Y282341D03*
X425901Y299410D03*
Y306410D03*
Y282410D03*
Y289410D03*
X418701Y299410D03*
Y306410D03*
Y282410D03*
Y289410D03*
X440301Y299410D03*
Y306410D03*
X433101Y299410D03*
Y306410D03*
X447648Y299341D03*
Y306341D03*
X440301Y282410D03*
Y289410D03*
X433101Y282410D03*
Y289410D03*
X440194Y332291D03*
Y325291D03*
X655550Y7490D03*
Y14490D03*
X656170Y574690D03*
Y581690D03*
X721500Y60500D03*
Y53500D03*
X721900Y544100D03*
Y537100D03*
X1027256Y315841D03*
Y322841D03*
X1020756Y315841D03*
Y322841D03*
X1033809Y320410D03*
Y313410D03*
X1017909Y299410D03*
Y306410D03*
Y282410D03*
Y289410D03*
X1025109Y299410D03*
Y306410D03*
Y282410D03*
Y289410D03*
X1032309Y299410D03*
Y306410D03*
Y282410D03*
Y289410D03*
X1083709Y275410D03*
Y268410D03*
X1076509Y275410D03*
Y268410D03*
X1069309Y275410D03*
Y268410D03*
X1062109Y275410D03*
Y268410D03*
X1054909Y275410D03*
Y268410D03*
X1047656Y275441D03*
Y268441D03*
X1082209Y327910D03*
Y334910D03*
X1077009Y320410D03*
Y313410D03*
X1084209Y320410D03*
Y313410D03*
X1091409Y320410D03*
Y313410D03*
X1082709Y282410D03*
Y289410D03*
X1097256Y299341D03*
Y306341D03*
Y289341D03*
Y282341D03*
X1082709Y299410D03*
Y306410D03*
X1089909Y299410D03*
Y306410D03*
Y282410D03*
Y289410D03*
X1075009Y327910D03*
Y334910D03*
X1069809Y320410D03*
Y313410D03*
X1062609Y320410D03*
Y313410D03*
X1055409Y320410D03*
Y313410D03*
X1048209Y320410D03*
Y313410D03*
X1041009Y320410D03*
Y313410D03*
X1067809Y327910D03*
Y334910D03*
X1060609Y327910D03*
Y334910D03*
X1053356Y327941D03*
Y334941D03*
X1045956Y327941D03*
Y334941D03*
X1075509Y299410D03*
Y306410D03*
Y282410D03*
Y289410D03*
X1068309Y299410D03*
Y306410D03*
Y282410D03*
Y289410D03*
X1039509Y282410D03*
Y289410D03*
X1061109Y299410D03*
Y306410D03*
X1053909Y299410D03*
Y306410D03*
X1061109Y282410D03*
Y289410D03*
X1053909Y282410D03*
Y289410D03*
X1046709Y299410D03*
Y306410D03*
Y282410D03*
Y289410D03*
X1039509Y299410D03*
Y306410D03*
X1088900Y332800D03*
Y325800D03*
X1105256Y322341D03*
Y315341D03*
X1098609Y320410D03*
Y313410D03*
X1382000Y119500D03*
Y112500D03*
X1384500Y524500D03*
X1376500D03*
X1365413Y524149D03*
X1384500Y531500D03*
X1376500D03*
X1365413Y531149D03*
X1521668Y602139D03*
Y609139D03*
X1528168Y602139D03*
Y609139D03*
X1514668Y602139D03*
Y609139D03*
X1480200Y601099D03*
Y608099D03*
X1487200Y601099D03*
Y608099D03*
X1493700Y601139D03*
Y608139D03*
X1601106Y459700D03*
Y452700D03*
X1607614Y459696D03*
Y452696D03*
X1621900Y487300D03*
Y480300D03*
X1628500Y487000D03*
Y480000D03*
X1803495Y66060D03*
Y73060D03*
X1809995Y66060D03*
Y73060D03*
X1858769Y55803D03*
Y62803D03*
X1871500Y128000D03*
Y135000D03*
X1902340Y105391D03*
Y112391D03*
X1910500Y112000D03*
Y119000D03*
G54D25*
X11980Y21330D03*
X15480D03*
X5440Y21090D03*
X8940D03*
X17276Y59655D03*
X13776D03*
X20260Y49500D03*
X16760D03*
X8500Y62800D03*
X5000D03*
X34900Y164100D03*
X38400D03*
X4800Y197300D03*
X8300D03*
X6500Y236000D03*
X10000D03*
X-8700Y449350D03*
X-5200D03*
X-13400Y502800D03*
X-9900D03*
X-13400Y506300D03*
X-9900D03*
X37568Y480095D03*
X34068D03*
X6500Y570300D03*
X3000D03*
X7000Y534500D03*
X3500D03*
X-1750Y574100D03*
X-5250D03*
X58308Y-14773D03*
X54808D03*
X58308Y-17864D03*
X54808D03*
X58316Y-11754D03*
X54816D03*
X93714Y124724D03*
X97214D03*
X94000Y118500D03*
X97500D03*
X67000Y183000D03*
X70500D03*
X67000Y186500D03*
X70500D03*
X51500Y163000D03*
X55000D03*
X66000Y166500D03*
X69500D03*
X51500Y159500D03*
X55000D03*
X93500Y223800D03*
X97000D03*
X105800Y338200D03*
X102300D03*
X76600Y331900D03*
X73100D03*
X92000Y338200D03*
X95500D03*
X92000Y327500D03*
X95500D03*
X76600Y307300D03*
X80100D03*
X87500Y313000D03*
X91000D03*
X67500Y319500D03*
X64000D03*
X73000Y324500D03*
X76500D03*
X73000Y328000D03*
X76500D03*
X65620Y296680D03*
X62120D03*
X65520Y300680D03*
X62020D03*
X92370Y293020D03*
X88870D03*
X65000Y351500D03*
X68500D03*
X61100Y343150D03*
X64600D03*
X58000Y351000D03*
X54500D03*
X55130Y385820D03*
X51630D03*
X55130Y395520D03*
X51630D03*
X73730Y396080D03*
X70230D03*
X73730Y392580D03*
X70230D03*
X55130Y392020D03*
X51630D03*
X73730Y403380D03*
X70230D03*
X55110Y382340D03*
X51610D03*
X52330Y403420D03*
X48830D03*
X52330Y399920D03*
X48830D03*
X73730Y414180D03*
X70230D03*
X73730Y417680D03*
X70230D03*
X57990Y423170D03*
X54490D03*
X57990Y419670D03*
X54490D03*
X69730Y424980D03*
X66230D03*
X69730Y428480D03*
X66230D03*
X73730Y406880D03*
X70230D03*
X75830Y531361D03*
X79330D03*
X75846Y528307D03*
X79346D03*
X123392Y31978D03*
X119892D03*
X123392Y-6000D03*
X119892D03*
X123392Y69778D03*
X119892D03*
X130800Y214600D03*
X127300D03*
X130700Y278700D03*
X127200D03*
X130500Y246600D03*
X127000D03*
X130600Y310800D03*
X127100D03*
X130600Y342600D03*
X127100D03*
X130500Y374600D03*
X127000D03*
X151254Y417659D03*
X154754D03*
X151361Y420954D03*
X154861D03*
X151341Y424439D03*
X154841D03*
X164897Y410444D03*
X161397D03*
X164667Y407412D03*
X161167D03*
X123792Y532800D03*
X120292D03*
X123392Y570778D03*
X119892D03*
X123392Y608800D03*
X119892D03*
X251700Y366800D03*
X248200D03*
X252700Y362800D03*
X249200D03*
X252700Y358800D03*
X249200D03*
X252700Y354300D03*
X249200D03*
X252700Y349800D03*
X249200D03*
X313000Y253000D03*
X316500D03*
X313000Y256500D03*
X316500D03*
X312063Y341509D03*
X315563D03*
X312063Y345009D03*
X315563D03*
X343802Y496030D03*
X340302D03*
X444378Y117880D03*
X440878D03*
X452500Y278500D03*
X456000D03*
X438934Y270091D03*
X442434D03*
X461500Y301000D03*
X458000D03*
X461500Y295000D03*
X458000D03*
X457900Y283000D03*
X461400D03*
X458000Y307000D03*
X461500D03*
X458000Y304000D03*
X461500D03*
X458000Y310000D03*
X461500D03*
Y298000D03*
X458000D03*
X457900Y286000D03*
X461400D03*
X457900Y289000D03*
X461400D03*
X507472Y255647D03*
X510972D03*
X512430Y258547D03*
X515930D03*
X649600Y-9000D03*
X653100D03*
X659755Y-8699D03*
X656255D03*
X658300Y-4800D03*
X654800D03*
X656405Y89566D03*
X659905D03*
X656406Y92766D03*
X659906D03*
X653000Y264800D03*
X649500D03*
X653000Y261300D03*
X649500D03*
X646000Y272000D03*
X649500D03*
X646000Y268500D03*
X649500D03*
X644400Y302000D03*
X640900D03*
X644400Y316300D03*
X640900D03*
X644000Y327000D03*
X640500D03*
X644890Y337000D03*
X641390D03*
X644890Y332000D03*
X641390D03*
X644000Y322000D03*
X640500D03*
X644400Y312000D03*
X640900D03*
X644400Y307000D03*
X640900D03*
X653000Y320500D03*
X649500D03*
X653000Y316500D03*
X649500D03*
X653000Y333500D03*
X649500D03*
X612307Y470019D03*
X615807D03*
X660500Y494500D03*
X660320Y585600D03*
X663820D03*
X683950Y14500D03*
X687450D03*
X684726Y18015D03*
X688226D03*
X703919Y79550D03*
X700419D03*
X703919Y82850D03*
X700419D03*
X664888Y89189D03*
X668388D03*
X664888Y92766D03*
X668388D03*
X683000Y256000D03*
X686500D03*
X702000Y223500D03*
X705500D03*
X702036Y269061D03*
X705536D03*
X702011Y272561D03*
X705511D03*
X690000Y300500D03*
X693500D03*
X690251Y330500D03*
X693751D03*
X690251Y335500D03*
X693751D03*
X690420Y325500D03*
X693920D03*
X709100Y303600D03*
X712600D03*
Y300100D03*
X709100D03*
X690420Y320500D03*
X693920D03*
X690000Y305500D03*
X693500D03*
X686784Y291412D03*
X690284D03*
X681000Y317500D03*
X684500D03*
X681000Y321500D03*
X684500D03*
X681000Y333000D03*
X684500D03*
X670500Y494500D03*
X667000D03*
X664000D03*
X677400Y581900D03*
X673900D03*
X683600Y578500D03*
X687100D03*
X773000Y31978D03*
X769500D03*
X773000Y-6000D03*
X769500D03*
X773000Y69778D03*
X769500D03*
X780032Y214689D03*
X776532D03*
X780032Y246689D03*
X776532D03*
X780032Y278689D03*
X776532D03*
X772300Y252000D03*
X768800D03*
X772100Y220000D03*
X768600D03*
X780032Y310689D03*
X776532D03*
X771900Y284100D03*
X768400D03*
X771900Y315900D03*
X768400D03*
X779982Y374689D03*
X776482D03*
X780032Y342689D03*
X776532D03*
X772100Y380200D03*
X768600D03*
X772400Y348200D03*
X768900D03*
X726500Y574500D03*
X730000D03*
X773000Y570778D03*
X769500D03*
X773400Y532800D03*
X769900D03*
X773000Y608800D03*
X769500D03*
X806500Y415500D03*
X810000D03*
X806500Y418500D03*
X810000D03*
X806500Y412500D03*
X810000D03*
X898100Y341000D03*
X901600D03*
X899500Y367500D03*
X896000D03*
X899500Y364500D03*
X896000D03*
X899500Y361500D03*
X896000D03*
X899500Y355500D03*
X896000D03*
X899500Y358500D03*
X896000D03*
X898100Y344800D03*
X901600D03*
X961139Y253100D03*
X964639D03*
X961139Y256600D03*
X964639D03*
X961630Y340840D03*
X965130D03*
X961630Y344340D03*
X965130D03*
X1093800Y115500D03*
X1090300D03*
X1092000Y270000D03*
X1088500D03*
X1043300Y490900D03*
X1046800D03*
X1105456Y278241D03*
X1101956D03*
X1107700Y304100D03*
X1111200D03*
X1107756Y310241D03*
X1111256D03*
X1107756Y307241D03*
X1111256D03*
X1107756Y286141D03*
X1111256D03*
X1111300Y294500D03*
X1107800D03*
X1111300Y298100D03*
X1107800D03*
X1111300Y301100D03*
X1107800D03*
X1107756Y289341D03*
X1111256D03*
X1107756Y282941D03*
X1111256D03*
X1165400Y257726D03*
X1161900D03*
X1165522Y261143D03*
X1162022D03*
X1271550Y111670D03*
X1275050D03*
X1271550Y125857D03*
X1275050D03*
X1271550Y129670D03*
X1275050D03*
X1271139Y117373D03*
X1274639D03*
X1275050Y107918D03*
X1271550D03*
X1264550Y107670D03*
X1268050D03*
Y129670D03*
X1264550D03*
X1268050Y125670D03*
X1264550D03*
X1268050Y111670D03*
X1264550D03*
X1252300Y130700D03*
X1255800D03*
X1252300Y134700D03*
X1255800D03*
X1248700Y473700D03*
X1245200D03*
X1245300Y477300D03*
X1248800D03*
X1330100Y71510D03*
X1333600D03*
X1330100Y68000D03*
X1333600D03*
X1291524Y214952D03*
X1288024D03*
X1303072Y249560D03*
X1299572D03*
X1303171Y245893D03*
X1299671D03*
X1299750Y241500D03*
X1303250D03*
X1288000Y219000D03*
X1291500D03*
X1287670Y231199D03*
X1291170D03*
X1291000Y237500D03*
X1287500D03*
Y243500D03*
X1291000D03*
X1303040Y264840D03*
X1299540D03*
X1303040Y260840D03*
X1299540D03*
X1299589Y257102D03*
X1303089D03*
X1303072Y252660D03*
X1299572D03*
X1287500Y240500D03*
X1291000D03*
X1298000Y219000D03*
X1294500D03*
X1341500Y329100D03*
Y332700D03*
Y325600D03*
X1340969Y354526D03*
X1337469D03*
X1281350Y488700D03*
X1284850D03*
X1367089Y2676D03*
X1370589D03*
X1367400Y34700D03*
X1370900D03*
X1382080Y328782D03*
X1385580D03*
X1345000Y329100D03*
Y332700D03*
Y325600D03*
X1346800Y340800D03*
X1343300D03*
X1385300Y341500D03*
X1381800D03*
X1385850Y286700D03*
X1389350D03*
X1385850Y283600D03*
X1389350D03*
X1388750Y293500D03*
X1392250D03*
X1385850Y289700D03*
X1389350D03*
X1395512Y339812D03*
X1399012D03*
X1385300Y332000D03*
X1381800D03*
X1386300Y338400D03*
X1382800D03*
X1386300Y335200D03*
X1382800D03*
X1343300Y347800D03*
X1346800D03*
Y344300D03*
X1343300D03*
X1381800Y344500D03*
X1385300D03*
X1385900Y353803D03*
X1382400D03*
X1381780Y356848D03*
X1385280D03*
X1385300Y347518D03*
X1381800D03*
X1359649Y358155D03*
X1356149D03*
X1369707Y393568D03*
X1373207D03*
X1385920Y350658D03*
X1382420D03*
X1358300Y443800D03*
X1361800D03*
X1391341Y498523D03*
X1394841D03*
X1391341Y494223D03*
X1394841D03*
X1388841Y482923D03*
X1392341D03*
X1388841Y487323D03*
X1392341D03*
X1371041Y497423D03*
X1374541D03*
X1368941Y482123D03*
X1372441D03*
X1371041Y493023D03*
X1374541D03*
X1368841Y486523D03*
X1372341D03*
X1354871Y512287D03*
X1351371D03*
X1394841Y498523D03*
X1398341D03*
X1394841Y494223D03*
X1398341D03*
X1392341Y482923D03*
X1395841D03*
X1392341Y487323D03*
X1395841D03*
X1372341Y486523D03*
X1375841D03*
X1374541Y493023D03*
X1378041D03*
X1374541Y497423D03*
X1378041D03*
X1372441Y482123D03*
X1375941D03*
X1371400Y581556D03*
X1374900D03*
X1370600Y613100D03*
X1374100D03*
X1460577Y163412D03*
X1464077D03*
Y159912D03*
X1460577D03*
X1419511Y176559D03*
X1423011D03*
Y173059D03*
X1419511D03*
Y170059D03*
X1423011D03*
X1419511Y166559D03*
X1423011D03*
Y163559D03*
X1419511D03*
Y179559D03*
X1423011D03*
X1419511Y186059D03*
X1423011D03*
X1419511Y183059D03*
X1423011D03*
X1452659Y188296D03*
X1456159D03*
X1438072Y189932D03*
X1434572D03*
X1458500Y252000D03*
X1462000D03*
X1435500Y311400D03*
X1439000D03*
X1435500Y308400D03*
X1439000D03*
X1435500Y305400D03*
X1439000D03*
X1434700Y315100D03*
X1438200D03*
X1453811Y369748D03*
X1457311D03*
X1449564Y362601D03*
X1453064D03*
X1451000Y448000D03*
X1454500D03*
X1451000Y437000D03*
X1454500D03*
X1451000Y442500D03*
X1454500D03*
X1435500Y437000D03*
X1439000D03*
X1435500Y448000D03*
X1439000D03*
X1435500Y453500D03*
X1439000D03*
X1451000Y431500D03*
X1454500D03*
X1435500Y442500D03*
X1439000D03*
X1444614Y482523D03*
X1448114D03*
X1444614Y478123D03*
X1448114D03*
X1444641Y489723D03*
X1448141D03*
X1444641Y494123D03*
X1448141D03*
X1421014Y482323D03*
X1424514D03*
X1421014Y477923D03*
X1424514D03*
X1420841Y494323D03*
X1424341D03*
X1420841Y489923D03*
X1424341D03*
X1424514Y477923D03*
X1428014D03*
X1448141Y489723D03*
X1451641D03*
X1448141Y494123D03*
X1451641D03*
X1448114Y482523D03*
X1451614D03*
X1448114Y478123D03*
X1451614D03*
X1424341Y489923D03*
X1427841D03*
X1424341Y494323D03*
X1427841D03*
X1424514Y482323D03*
X1428014D03*
X1436060Y541455D03*
X1432560D03*
X1436060Y544955D03*
X1432560D03*
X1501900Y12541D03*
X1505400D03*
X1526000Y64500D03*
X1520106Y93976D03*
X1516606D03*
X1497500Y76000D03*
X1494000D03*
X1497500Y79500D03*
X1494000D03*
X1526337Y136439D03*
X1522837D03*
X1520106Y97976D03*
X1516606D03*
X1521071Y104358D03*
X1517571D03*
X1521071Y108358D03*
X1517571D03*
X1520610Y120361D03*
X1517110D03*
X1520610Y116361D03*
X1517110D03*
X1472072Y142112D03*
X1468572D03*
X1520250Y215000D03*
X1516750D03*
X1521500Y194500D03*
X1518000D03*
X1523500Y189000D03*
X1520000D03*
Y186000D03*
X1523500D03*
X1518979Y179889D03*
X1522479D03*
X1494000Y194000D03*
X1490500D03*
X1480250Y180000D03*
X1476750D03*
X1477442Y190269D03*
X1473942D03*
Y187269D03*
X1477442D03*
X1468300Y181400D03*
X1471800D03*
X1470223Y156988D03*
X1473723D03*
X1508750Y177000D03*
X1505250D03*
X1508750Y174000D03*
X1505250D03*
X1473123Y163088D03*
X1476623D03*
X1473123Y160088D03*
X1476623D03*
X1469700Y211850D03*
X1473200D03*
X1468300Y184400D03*
X1471800D03*
X1480250Y176800D03*
X1476750D03*
X1515312Y231532D03*
X1518812D03*
X1515250Y237000D03*
X1518750D03*
X1470729Y240547D03*
X1467229D03*
X1467750Y220000D03*
X1471250D03*
X1467750Y223500D03*
X1471250D03*
X1467750Y227000D03*
X1471250D03*
X1525422Y227625D03*
Y230625D03*
X1526610Y336680D03*
Y333680D03*
X1480500Y323500D03*
X1477000D03*
X1526660Y315900D03*
X1487000Y322400D03*
X1490500D03*
X1498430Y311510D03*
X1501930D03*
X1513060Y319170D03*
X1509560D03*
X1503519Y283694D03*
X1507019D03*
X1506996Y280694D03*
X1503496D03*
X1487000Y325500D03*
X1490500D03*
X1522810Y327640D03*
X1519310D03*
X1479200Y401900D03*
X1475700D03*
X1479000Y394900D03*
X1475500D03*
X1470100Y360500D03*
X1466600D03*
X1470200Y357500D03*
X1466700D03*
X1469750Y369500D03*
X1466250D03*
X1469750Y366500D03*
X1466250D03*
X1475755Y376254D03*
X1479255D03*
X1475500Y398400D03*
X1479000D03*
X1502302Y410686D03*
X1505802D03*
X1524100Y494123D03*
X1527600D03*
X1511000Y526000D03*
X1507500D03*
X1474300Y615500D03*
X1477800D03*
X1508600Y616416D03*
X1512100D03*
X1508600Y623110D03*
X1512100D03*
X1586600Y-13300D03*
Y-9600D03*
X1555450Y81200D03*
X1558950D03*
X1529500Y64500D03*
X1552050Y78000D03*
X1555550D03*
X1548850Y81200D03*
X1552350D03*
X1587100Y91000D03*
X1583600D03*
X1534436Y95154D03*
X1537936D03*
X1534436Y85354D03*
X1537936D03*
X1534436Y88754D03*
X1537936D03*
X1534436Y91954D03*
X1537936D03*
X1536000Y64500D03*
X1532500D03*
X1534889Y34238D03*
X1531389D03*
X1536000Y68000D03*
X1532500D03*
X1585000Y137000D03*
X1581500D03*
X1584450Y155600D03*
X1580950D03*
Y152600D03*
X1584450D03*
Y146100D03*
X1580950D03*
Y149200D03*
X1584450D03*
X1577271Y101142D03*
X1573771D03*
X1563502Y117500D03*
X1560002D03*
X1553500D03*
X1557000D03*
X1543169Y143954D03*
X1539669D03*
X1584599Y143038D03*
X1581099D03*
X1584599Y140038D03*
X1581099D03*
X1545500Y112500D03*
X1549000D03*
X1545500Y109000D03*
X1549000D03*
X1534436Y101554D03*
X1537936D03*
X1534436Y98354D03*
X1537936D03*
X1534750Y152065D03*
X1538250D03*
X1534750Y148565D03*
X1538250D03*
X1534750Y155565D03*
X1538250D03*
X1580750Y166000D03*
X1584250D03*
X1584099Y162838D03*
X1580599D03*
X1584099Y159838D03*
X1580599D03*
X1580750Y169000D03*
X1584250D03*
X1578920Y190920D03*
X1575420D03*
X1556000Y257250D03*
X1552500D03*
X1556008Y260918D03*
X1552508D03*
X1528750Y241500D03*
X1532250D03*
X1536000Y260500D03*
X1532500D03*
X1528922Y227625D03*
Y230625D03*
X1532650Y253713D03*
X1536150D03*
X1566817Y243681D03*
X1570317D03*
X1552500Y264000D03*
X1556000D03*
X1555500Y247000D03*
X1552000D03*
X1555500Y250500D03*
X1552000D03*
X1587971Y311952D03*
X1530110Y336680D03*
Y333680D03*
X1530160Y315900D03*
X1576100Y292000D03*
X1572600D03*
X1562500Y296050D03*
X1566000D03*
X1589250Y379500D03*
Y385500D03*
Y382500D03*
Y388500D03*
X1546032Y352846D03*
X1549532D03*
Y347696D03*
X1546032D03*
X1585352Y366117D03*
X1588852D03*
X1585352Y369117D03*
X1588852D03*
X1574250Y418000D03*
X1577750D03*
X1547269Y448438D03*
X1543769D03*
X1546972Y453999D03*
X1543472D03*
X1535200Y494123D03*
X1531700D03*
X1583255Y502596D03*
X1579755D03*
X1583255Y497596D03*
X1579755D03*
X1576456Y491096D03*
X1572956D03*
X1576456Y494596D03*
X1572956D03*
X1588300Y583000D03*
X1574569Y589228D03*
X1578069D03*
X1581000Y603500D03*
X1584500D03*
X1581000Y600500D03*
X1584500D03*
X1557039Y614627D03*
X1560539D03*
X1538110Y598430D03*
X1541610D03*
X1548371Y594310D03*
X1551871D03*
X1552172Y604536D03*
X1548672D03*
X1538430Y604180D03*
X1541930D03*
X1551871Y597810D03*
X1548371D03*
X1551871Y601310D03*
X1548371D03*
X1549075Y619000D03*
X1552575D03*
X1590100Y-13300D03*
X1627250Y17000D03*
X1630750D03*
X1634250D03*
X1637750D03*
X1613250Y18000D03*
X1609750D03*
X1605000Y-1100D03*
X1608500D03*
X1590100Y-9600D03*
X1616250Y17000D03*
X1619750D03*
X1624750Y72000D03*
X1628250D03*
X1614250Y78000D03*
X1610750D03*
X1628500Y80300D03*
X1632000D03*
X1624750Y69000D03*
X1628250D03*
X1603550Y58200D03*
X1607050D03*
X1609450Y34500D03*
X1605950D03*
X1613550Y34700D03*
X1617050D03*
X1617727Y46763D03*
X1621227D03*
X1622750Y43311D03*
X1619250D03*
X1645000Y35500D03*
X1648500D03*
X1609099Y86038D03*
X1612599D03*
X1611059Y46684D03*
X1614559D03*
X1598439Y128600D03*
X1601939D03*
X1606500Y110000D03*
X1603000D03*
X1604500Y107000D03*
X1601000D03*
X1599401Y138165D03*
X1595901D03*
X1599400Y135092D03*
X1595900D03*
X1594600Y131600D03*
X1598100D03*
X1595300Y121500D03*
X1591800D03*
X1595250Y118500D03*
X1591750D03*
X1594150Y115500D03*
X1590650D03*
X1641854Y138592D03*
X1645354D03*
X1635480Y146470D03*
X1638980D03*
X1646111Y150750D03*
X1642611D03*
X1645601Y144750D03*
X1649101D03*
X1639250Y115500D03*
X1635750D03*
X1648090Y118640D03*
X1616750Y131500D03*
X1620250D03*
X1626750Y137500D03*
X1623250D03*
X1616592Y156055D03*
X1620092D03*
X1616599Y137538D03*
X1620099D03*
X1622250Y109500D03*
X1618750D03*
X1622750Y96000D03*
X1626250D03*
X1622750Y99500D03*
X1626250D03*
X1622750Y103000D03*
X1626250D03*
X1608250Y96000D03*
X1611750D03*
X1622888Y116340D03*
X1619388D03*
X1616498Y122472D03*
X1619998D03*
X1645597Y147750D03*
X1649097D03*
X1623700Y143900D03*
X1620200D03*
X1622791Y113140D03*
X1619291D03*
X1644950Y189600D03*
X1648450D03*
Y192600D03*
X1644950D03*
X1619846Y188276D03*
X1623346D03*
X1619781Y191683D03*
X1623281D03*
X1599740Y200550D03*
X1596240D03*
X1629380Y179436D03*
X1632880D03*
X1591471Y311952D03*
X1592750Y379500D03*
Y385500D03*
Y382500D03*
Y388500D03*
X1626200Y352050D03*
X1629700D03*
X1591852Y366117D03*
X1595352D03*
X1591852Y372117D03*
X1595352D03*
X1591852Y369117D03*
X1595352D03*
X1605250Y430000D03*
X1608750D03*
X1622783Y419548D03*
X1626283D03*
X1619500Y494000D03*
X1616000D03*
X1591800Y583000D03*
X1628600Y559200D03*
X1632100D03*
X1615000Y555200D03*
X1618500D03*
X1628600D03*
X1632100D03*
X1609100Y582500D03*
X1612600D03*
X1609100Y578500D03*
X1612600D03*
X1618000Y576500D03*
X1621500D03*
X1618000Y572500D03*
X1621500D03*
X1615000Y559200D03*
X1618500D03*
X1619500Y586880D03*
X1616000D03*
X1611000Y596500D03*
X1607500D03*
X1619500Y599500D03*
X1616000D03*
X1619500Y603000D03*
X1616000D03*
X1610400Y608200D03*
X1606900D03*
X1611000Y593000D03*
X1607500D03*
X1610400Y604700D03*
X1606900D03*
X1619500Y590380D03*
X1616000D03*
X1661250Y16500D03*
X1664750D03*
X1711250Y68500D03*
X1707750D03*
Y72000D03*
X1711250D03*
X1686250Y80000D03*
X1682750D03*
X1686250Y83000D03*
X1682750D03*
X1662500Y58800D03*
X1659000D03*
X1671700Y59300D03*
X1675200D03*
X1673750Y46000D03*
X1677250D03*
X1671700Y55800D03*
X1675200D03*
X1680736Y47039D03*
X1684236D03*
X1684250Y44000D03*
X1680750D03*
X1688350Y71000D03*
X1684850D03*
Y68000D03*
X1688350D03*
X1685661Y60161D03*
X1689161D03*
X1685661Y63161D03*
X1689161D03*
X1690250Y49000D03*
X1693750D03*
X1689750Y54000D03*
X1693250D03*
X1692272Y60161D03*
X1695772D03*
X1686125Y51223D03*
X1682625D03*
X1682638Y54311D03*
X1686138D03*
X1682750Y86000D03*
X1686250D03*
X1682750Y89000D03*
X1686250D03*
Y92000D03*
X1682750D03*
X1686250Y95000D03*
X1682750D03*
X1702749Y69233D03*
X1699249D03*
X1651590Y118640D03*
X1657500Y128000D03*
X1654000D03*
X1656599Y189608D03*
X1653099D03*
X1660679Y179278D03*
X1657179D03*
Y175778D03*
X1660679D03*
X1653099Y192608D03*
X1656599D03*
X1711535Y172070D03*
X1708035D03*
X1710811Y165400D03*
X1711506Y168970D03*
X1708006D03*
X1658800Y327300D03*
X1662300D03*
X1705683Y580727D03*
X1709183D03*
Y584727D03*
X1705683D03*
X1699780Y558817D03*
X1696280D03*
X1699780Y555517D03*
X1696280D03*
X1667680Y587000D03*
X1664180D03*
X1656000Y578500D03*
X1659500D03*
X1656000Y582000D03*
X1659500D03*
X1703500Y604500D03*
X1707000D03*
X1703500Y595500D03*
X1707000D03*
X1703500Y600000D03*
X1707000D03*
X1659500Y597500D03*
X1656000D03*
X1659500Y594000D03*
X1656000D03*
X1659500Y613500D03*
X1656000D03*
X1659500Y610000D03*
X1656000D03*
X1667500Y606000D03*
X1664000D03*
X1667500Y602500D03*
X1664000D03*
X1667680Y590500D03*
X1664180D03*
X1768100Y31700D03*
X1771600D03*
X1759900Y71300D03*
X1763400D03*
X1773750Y94500D03*
X1770250D03*
Y89500D03*
X1773750D03*
X1763300Y68300D03*
X1759800D03*
X1731960Y83830D03*
X1728460D03*
X1743000Y51600D03*
X1739500D03*
Y57800D03*
X1743000D03*
X1756879Y87674D03*
X1760379D03*
X1756961Y93081D03*
X1760461D03*
X1737589Y63639D03*
X1734089D03*
X1723681Y89100D03*
X1727181D03*
X1772211Y67650D03*
Y70650D03*
X1743000Y54700D03*
X1739500D03*
X1770250Y99500D03*
X1773750D03*
X1751779Y151165D03*
X1748279D03*
X1730289Y130319D03*
X1726789D03*
X1730289Y126381D03*
X1726789D03*
X1761035Y116600D03*
X1764535D03*
X1770250Y104500D03*
X1773750D03*
X1761035Y113400D03*
X1764535D03*
X1725250Y191500D03*
X1728750D03*
X1714311Y165400D03*
X1734930Y228440D03*
X1738430D03*
X1745920Y228410D03*
X1742420D03*
X1759400Y243400D03*
X1755900D03*
X1759400Y246400D03*
X1755900D03*
X1765000Y517000D03*
X1768500D03*
X1774000Y555500D03*
X1770500D03*
X1741200Y559200D03*
X1744700D03*
X1773900Y562450D03*
X1770400D03*
X1769000Y581900D03*
X1772500D03*
X1769000Y578900D03*
X1772500D03*
X1746292Y578251D03*
X1742792D03*
X1769050Y588100D03*
X1772550D03*
X1745200Y555363D03*
X1741700D03*
X1769050Y585000D03*
X1772550D03*
X1746269Y581351D03*
X1742769D03*
X1769000Y591100D03*
X1772500D03*
X1768397Y613578D03*
X1771897D03*
X1730232Y618712D03*
X1726732D03*
X1832250Y17500D03*
X1828750D03*
X1835250D03*
X1784415Y15168D03*
X1780915D03*
X1784415Y18168D03*
X1780915D03*
X1804500Y16600D03*
X1801000D03*
X1797000D03*
X1793500D03*
X1782200Y21700D03*
X1778700D03*
X1819930Y52029D03*
X1823430D03*
X1775711Y67650D03*
Y70650D03*
X1804814Y84623D03*
X1801314D03*
X1819136Y42120D03*
X1822636D03*
X1792127Y125981D03*
X1788627D03*
Y122981D03*
X1792127D03*
X1814900Y137600D03*
X1811400D03*
Y140600D03*
X1814900D03*
X1783300Y519100D03*
X1786800D03*
X1809052Y523001D03*
X1812552D03*
X1821052D03*
X1817552D03*
X1824750Y498000D03*
X1828250D03*
X1807600Y515600D03*
X1804100D03*
X1825552Y537501D03*
X1822052D03*
X1825552Y541001D03*
X1822052D03*
X1819552Y581301D03*
X1816052D03*
X1786200Y574700D03*
X1789700D03*
Y580900D03*
X1786200D03*
X1805100Y567500D03*
X1801600D03*
X1822000Y576000D03*
X1818500D03*
X1786200Y577800D03*
X1789700D03*
X1812000Y606000D03*
X1808500D03*
X1838750Y17500D03*
X1873336Y22480D03*
X1869836D03*
X1873336Y18980D03*
X1869836D03*
X1883993Y13300D03*
X1880493D03*
X1883951Y9897D03*
X1880451D03*
X1845197Y27000D03*
X1841697D03*
X1848486Y29680D03*
X1851986D03*
X1848386Y17980D03*
X1851886D03*
X1876993Y13300D03*
X1880493D03*
X1876951Y9897D03*
X1880451D03*
X1862539Y78537D03*
X1866039D03*
Y75138D03*
X1862539D03*
X1856163Y150948D03*
X1859663D03*
X1863500Y151000D03*
X1867000D03*
X1893150Y155600D03*
X1889650D03*
X1892050Y152100D03*
X1888550D03*
X1885750Y130500D03*
X1889250D03*
X1871290Y121480D03*
X1867790D03*
X1871290Y117980D03*
X1867790D03*
X1891250Y119000D03*
X1894750D03*
X1891290Y115580D03*
X1894790D03*
X1897000Y209200D03*
X1847000Y216500D03*
X1850500D03*
X1893200Y170900D03*
X1889700D03*
X1893200Y167700D03*
X1889700D03*
X1893250Y174500D03*
X1889750D03*
X1892750Y159100D03*
X1889250D03*
X1896735Y231622D03*
Y228622D03*
X1892963Y231387D03*
X1889463D03*
X1892963Y228387D03*
X1889463D03*
X1896735Y225622D03*
X1847000Y222000D03*
X1850500D03*
X1847000Y240000D03*
X1850500D03*
X1847000Y243000D03*
X1850500D03*
X1847000Y246000D03*
X1850500D03*
X1847000Y228000D03*
X1850500D03*
X1847000Y237000D03*
X1850500D03*
X1847000Y225000D03*
X1850500D03*
Y234000D03*
X1847000D03*
X1850500Y231000D03*
X1847000D03*
X1858500Y445100D03*
X1855000D03*
Y441500D03*
X1858500D03*
X1895200Y445300D03*
X1898000Y451000D03*
X1894500D03*
X1865847Y500954D03*
X1869347D03*
X1865799Y504018D03*
X1869299D03*
X1862700Y491650D03*
X1859200D03*
X1854550Y505510D03*
X1858050D03*
X1862700Y488500D03*
X1859200D03*
X1896154Y563968D03*
Y560968D03*
Y566968D03*
X1894654Y569968D03*
X1855750Y545500D03*
X1852250D03*
Y542500D03*
X1855750D03*
X1871500Y579500D03*
X1875000D03*
X1872146Y533140D03*
X1875646D03*
X1869310D03*
X1865810D03*
X1852500Y530700D03*
X1849000D03*
X1845750Y542500D03*
X1849250D03*
X1841500Y552600D03*
X1838000D03*
X1861538Y572746D03*
X1865038D03*
X1859187Y534585D03*
X1862687D03*
X1859217Y531331D03*
X1862717D03*
X1913143Y-19572D03*
X1909643D03*
X1909661Y-16368D03*
X1913161D03*
X1908166Y67073D03*
X1904666D03*
X1901661Y67193D03*
X1898161D03*
X1920500Y71500D03*
X1924000D03*
X1898143Y70589D03*
X1901643D03*
X1904736Y70607D03*
X1908236D03*
X1959619Y136676D03*
X1956321Y149724D03*
D03*
X1952821D03*
X1920100Y143100D03*
X1923600D03*
X1914700Y137600D03*
X1918200D03*
X1942637Y103377D03*
X1939137D03*
X1951341Y187424D03*
X1954841D03*
X1951318Y181882D03*
X1954818D03*
X1912850Y196300D03*
X1909350D03*
X1900500Y209200D03*
X1930449Y183722D03*
X1926949D03*
X1930341Y188701D03*
X1926841D03*
X1919150Y163100D03*
X1922650D03*
X1933250Y157600D03*
X1936750D03*
X1898250Y191000D03*
X1901750D03*
X1918750Y171600D03*
X1922250D03*
X1918474Y175140D03*
X1921974D03*
X1902250Y187500D03*
X1898750D03*
X1900235Y231622D03*
Y228622D03*
Y225622D03*
X1917336Y231924D03*
X1913836D03*
X1925665Y239441D03*
X1922165D03*
X1917356Y228756D03*
X1913856D03*
X1925660Y236318D03*
X1922160D03*
X1913970Y239458D03*
X1910470D03*
X1913959Y236258D03*
X1910459D03*
X1910500Y445800D03*
X1914000D03*
X1926500D03*
X1923000D03*
X1898700Y445300D03*
X1905000Y451000D03*
X1901500D03*
X1929860Y486480D03*
X1933360D03*
X1934150Y475400D03*
X1930650D03*
X1934150Y478400D03*
X1930650D03*
X1944710Y484520D03*
X1941210D03*
X1931285Y583000D03*
X1927785D03*
X1931285Y579500D03*
X1927785D03*
X1931285Y575500D03*
X1927785D03*
X1931285Y572000D03*
X1927785D03*
X1899654Y563968D03*
Y560968D03*
Y566968D03*
X1898154Y569968D03*
X1921500Y549900D03*
X1918000D03*
X1921000Y554400D03*
X1917500D03*
X1927750Y611550D03*
X1931250D03*
X1929740Y594760D03*
X1926240D03*
Y591260D03*
X1929740D03*
X1921250Y596900D03*
X1917750D03*
Y600400D03*
X1921250D03*
X1963119Y136676D03*
X1966619D03*
X1963119D03*
X1959821Y149724D03*
X1968249Y149881D03*
X1971749D03*
X1965973Y169460D03*
X1969473D03*
X1963500Y518200D03*
X1967000D03*
X1966500Y545500D03*
X1963000D03*
X1966500Y540500D03*
X1963000D03*
X1971000Y603100D03*
X1967500D03*
G54D145*
X1523200Y432600D03*
X1518300D03*
G54D181*
X1741189Y162269D03*
X1745689D03*
X1750189D03*
X1736689D03*
X1732189D03*
X1727689D03*
X1723189D03*
X1718689D03*
X1723189Y169725D03*
X1718689D03*
X1727689D03*
X1732189D03*
X1736689D03*
X1741189D03*
X1745689D03*
X1750189D03*
X1721808Y598005D03*
X1781800Y585050D03*
G54D154*
X1651800Y92500D03*
Y87500D03*
X1624300Y90800D03*
X1651800Y97500D03*
G54D109*
X1236921Y337307D03*
G54D172*
X1712642Y99814D03*
G54D127*
X1449933Y49950D03*
X1469689Y49000D03*
X1697872Y116423D03*
X1682141Y136233D03*
X1705138Y114470D03*
X1709277Y120700D03*
X1715318Y128300D03*
G54D34*
X12290Y264640D03*
X18450Y267010D03*
X22970Y244400D03*
X28720Y244450D03*
X17120Y244220D03*
X24200Y267060D03*
X1969291Y486064D03*
Y497874D03*
G54D16*
X-17084Y467626D03*
X-16766Y500106D03*
X2934Y26933D03*
X23728Y18731D03*
X1826Y56447D03*
X47100Y327000D03*
X-5680Y524570D03*
X10932Y523601D03*
X14700Y517000D03*
X-7360Y512000D03*
X-2083Y513704D03*
X-1000Y479000D03*
X5689Y481983D03*
X27280Y510420D03*
X-6200Y505400D03*
X-6566Y568363D03*
X-9291Y535201D03*
X51090Y8080D03*
X53382Y-1173D03*
X91306Y157194D03*
X61356Y181000D03*
X61256Y186000D03*
X64187Y176332D03*
X104820Y195700D03*
X97800Y200800D03*
X86731Y189148D03*
X73500Y191500D03*
X97200Y265000D03*
X91600Y278700D03*
X53250Y302800D03*
X48550Y301650D03*
X64700Y310525D03*
X84300Y305700D03*
Y310700D03*
X61625Y283201D03*
X72904Y284898D03*
X84300Y289000D03*
X82050Y283951D03*
X77103Y283900D03*
X84866Y294213D03*
X84300Y299000D03*
X58600Y302700D03*
X72600Y310800D03*
X77500Y312500D03*
X53025Y337475D03*
X93500Y285000D03*
X101828Y371096D03*
X51923Y346164D03*
X60934Y362307D03*
X57395Y366795D03*
X55500Y371700D03*
X61914Y368731D03*
X60900Y348300D03*
X79100Y347000D03*
X49100Y354500D03*
X57800Y376100D03*
X60565Y380131D03*
X65000Y383000D03*
X74800Y379700D03*
X80200D03*
X62600Y375100D03*
X102160Y354780D03*
X101770Y363150D03*
X97472Y380934D03*
X71050Y478670D03*
X92326Y480398D03*
X115536Y213508D03*
X154130Y190186D03*
X162788Y200650D03*
X162800Y195600D03*
X150000Y199850D03*
Y194850D03*
X115525Y245372D03*
X115536Y277508D03*
Y309508D03*
Y341508D03*
X109500Y370000D03*
X206800Y246500D03*
X203947Y280933D03*
X206600Y372400D03*
X195233Y348402D03*
X239778Y274478D03*
X438187Y609864D03*
X579497Y202003D03*
X578980Y217884D03*
X592300Y220500D03*
X617400Y115800D03*
X605028Y119000D03*
X604977Y110200D03*
X606148Y229494D03*
X633410Y269610D03*
Y274610D03*
X656100Y275500D03*
X649800Y252600D03*
X652700Y270600D03*
X618279Y251393D03*
X632869Y293720D03*
X646520Y297400D03*
X657950Y296850D03*
X637681Y332390D03*
Y337390D03*
X620400Y463990D03*
X629600Y425100D03*
X622100Y417900D03*
X608800Y463475D03*
X609284Y480055D03*
X618800Y474500D03*
X619390Y469450D03*
X639120Y475620D03*
X608800Y468475D03*
Y473475D03*
X636500Y493924D03*
X627000Y478300D03*
X680200Y13100D03*
X714300Y-1900D03*
X724837Y13852D03*
X701525Y35610D03*
X720572Y88700D03*
X717420Y249920D03*
X679300Y261700D03*
X677800Y254100D03*
X667700Y275600D03*
X709949Y272647D03*
X706800Y278100D03*
X710700Y260200D03*
X723400Y250000D03*
X673922Y298078D03*
X686140Y298260D03*
X667900Y339000D03*
X710272Y281911D03*
X724000Y291700D03*
X705800Y301600D03*
X697521Y325500D03*
X697352Y335500D03*
Y330500D03*
X697120Y300349D03*
X678730Y362841D03*
X686619Y392600D03*
X691240Y390039D03*
X669194Y351206D03*
X674194D03*
X679194D03*
X684194D03*
X676900Y381800D03*
X679385Y388705D03*
X687427Y384926D03*
X721894Y501346D03*
X675080Y485570D03*
X696000Y496800D03*
X679700Y489400D03*
X686200Y511700D03*
X680000Y511800D03*
X711704Y525483D03*
X707850Y505700D03*
X680029Y577503D03*
X718200Y581000D03*
X713132Y609306D03*
X765144Y213508D03*
X759700Y232000D03*
X739500Y247500D03*
X749126Y220843D03*
X742897Y226773D03*
X739400Y253400D03*
X730000Y254675D03*
X754263Y254207D03*
X754846Y276340D03*
X765144Y245508D03*
X749090Y270250D03*
X765144Y277508D03*
X757956Y328095D03*
X729405Y290725D03*
X743600Y304100D03*
X737750Y298894D03*
X737912Y315500D03*
X764980Y287980D03*
X765144Y309508D03*
Y341508D03*
X760500Y359800D03*
X767155Y385550D03*
X764159Y373743D03*
X799620Y186547D03*
X798337Y181216D03*
X813700Y198900D03*
X804470Y186814D03*
X1248616Y133817D03*
X1261800Y154973D03*
X1262569Y147201D03*
X1252000Y145300D03*
X1252437Y140192D03*
X1260737Y133877D03*
X1251980Y106960D03*
X1250200Y122900D03*
X1240010Y144754D03*
X1257800Y120800D03*
X1220580Y179810D03*
X1323000Y83000D03*
X1335120Y94450D03*
X1337400Y72000D03*
X1328500Y92500D03*
X1336900Y61600D03*
X1281799Y193190D03*
X1306585Y258250D03*
X1308887Y285015D03*
X1316600Y305500D03*
X1336336Y333825D03*
X1332600Y506300D03*
X1379025Y-9799D03*
X1348945Y40264D03*
X1370975Y67225D03*
X1343260Y53770D03*
X1351488Y74000D03*
X1358500Y74500D03*
X1347500Y83000D03*
X1357000Y86640D03*
X1383171Y57549D03*
X1379110Y45033D03*
X1392149Y68006D03*
X1371910Y48800D03*
X1370849Y59349D03*
X1380500Y50500D03*
X1372300Y86400D03*
X1363500Y77400D03*
X1403264Y82000D03*
X1345257Y100000D03*
X1348615Y96239D03*
X1353500Y96959D03*
X1345500Y107529D03*
X1364700Y96440D03*
X1373850Y120450D03*
X1396470Y330014D03*
X1381431Y284259D03*
X1383700Y392300D03*
X1388900Y387800D03*
X1380872Y378098D03*
X1347081Y507919D03*
X1390500Y539000D03*
X1383074Y581963D03*
X1398010Y590040D03*
X1407422Y13139D03*
X1455347Y92065D03*
X1457000Y82000D03*
X1452232Y109500D03*
X1457300Y373600D03*
X1420075Y378375D03*
Y393402D03*
Y383375D03*
Y388402D03*
X1413735Y396302D03*
Y391302D03*
X1448000Y431500D03*
X1431900Y453500D03*
X1447500Y448000D03*
X1431900Y442600D03*
X1448000Y437000D03*
X1431900Y448000D03*
X1447700Y442500D03*
X1431900Y437100D03*
X1436358Y525142D03*
X1451533Y527867D03*
X1413600Y531300D03*
X1432560Y561160D03*
X1428791Y535512D03*
X1419600Y531500D03*
X1453533Y532667D03*
X1426870Y530800D03*
X1423800Y534800D03*
X1421560Y563455D03*
X1415582Y562904D03*
X1439822Y537382D03*
X1428281Y546119D03*
X1429026Y541026D03*
X1410950Y589670D03*
X1499875Y90481D03*
X1524000Y123300D03*
X1490674Y98787D03*
X1498810Y108290D03*
X1526813Y108958D03*
X1526513Y115769D03*
X1500455Y114388D03*
X1496726Y120588D03*
X1473100Y128950D03*
X1514425Y137980D03*
X1526310Y142190D03*
X1485755Y131671D03*
X1500806Y133339D03*
X1526744Y98265D03*
X1483366Y115902D03*
X1498660Y102746D03*
X1520150Y127600D03*
X1502165Y251200D03*
X1505946Y254432D03*
X1498600Y334800D03*
X1467262Y420711D03*
X1503400Y524663D03*
X1563200Y3400D03*
X1543500D03*
X1577269Y95344D03*
X1530101Y132671D03*
X1541765Y114000D03*
X1541831Y149030D03*
X1558042Y172448D03*
X1545802Y233529D03*
X1575645Y320664D03*
X1565244Y300934D03*
X1568524Y312885D03*
X1582800Y312100D03*
X1564400Y308383D03*
X1587032Y350996D03*
X1585155Y538574D03*
X1579680Y610279D03*
X1545407Y598393D03*
X1632006Y94500D03*
X1643500Y80400D03*
X1621100Y69600D03*
X1597987Y79500D03*
X1630826Y88087D03*
X1594452Y111377D03*
X1603300Y185100D03*
X1639258Y185620D03*
X1647852Y197374D03*
X1635621Y208259D03*
X1606849Y241210D03*
X1643775Y246137D03*
X1632128Y225472D03*
X1622000Y279495D03*
X1620159Y332004D03*
X1625400Y327667D03*
X1608764Y322440D03*
X1621800Y386300D03*
Y381500D03*
X1630800Y378500D03*
X1640266Y365500D03*
Y360500D03*
X1590154Y354762D03*
X1590037Y432515D03*
X1590581Y404170D03*
X1639113Y496734D03*
X1598700Y479225D03*
X1617771Y498714D03*
X1629530Y496374D03*
X1629500Y491500D03*
X1639271Y491135D03*
X1625094Y555200D03*
X1603919Y592750D03*
X1650869Y614200D03*
Y609200D03*
X1678400Y103000D03*
X1691439Y174354D03*
X1677600Y172700D03*
X1707100Y188300D03*
X1664390Y201163D03*
X1659643Y213505D03*
X1676924Y196731D03*
X1671688Y182925D03*
X1680769Y242605D03*
X1664762Y440735D03*
X1676041Y458884D03*
X1660834Y404934D03*
X1651754Y488025D03*
X1684650Y505200D03*
X1672159Y494042D03*
X1701617Y482706D03*
X1676800Y483800D03*
X1660680Y586750D03*
X1658369Y602250D03*
X1652499Y597950D03*
X1749085Y9177D03*
X1715100Y70500D03*
X1722251Y250532D03*
X1766077Y232681D03*
X1751900Y249700D03*
X1746900Y249804D03*
X1749462Y232955D03*
X1719560Y501770D03*
X1743000Y570000D03*
X1765300Y574700D03*
X1742381Y588530D03*
X1815150Y26650D03*
X1797700Y21018D03*
X1791500Y26918D03*
X1813795Y12165D03*
X1808795D03*
X1828874Y-13520D03*
X1819837Y21700D03*
X1786865Y22375D03*
X1829888Y10735D03*
X1817352Y36909D03*
X1812352Y36949D03*
X1797700Y36804D03*
X1792700Y36871D03*
X1794100Y70898D03*
X1807818Y124179D03*
X1827500Y144900D03*
X1809810Y155858D03*
X1790100Y154000D03*
X1807440Y165530D03*
X1836100Y179700D03*
X1807440Y169030D03*
Y162030D03*
X1826682Y196841D03*
X1784878Y496701D03*
X1825900Y523500D03*
X1832200Y567760D03*
X1831500Y544500D03*
X1831800Y552300D03*
X1809600Y582800D03*
X1793100Y578500D03*
X1816020Y571448D03*
X1812802Y578693D03*
X1829051Y591299D03*
X1822273Y595046D03*
X1788290Y612006D03*
X1838500Y40400D03*
X1856333Y34518D03*
X1894855Y142122D03*
X1893640Y147042D03*
X1888639D03*
X1887497Y105444D03*
X1881165Y105561D03*
X1886000Y156700D03*
X1885102Y101134D03*
X1876001Y105438D03*
X1861932Y146431D03*
X1869668Y146750D03*
X1848532Y144360D03*
X1897507Y124450D03*
X1883800Y210575D03*
X1854868Y184667D03*
X1836900Y165800D03*
X1889400Y191200D03*
X1896710Y194380D03*
X1847200Y202050D03*
X1840900Y179700D03*
X1845700D03*
X1858686Y180377D03*
X1885465Y166285D03*
X1855000Y167100D03*
X1864170Y211869D03*
X1892791Y200069D03*
X1884000Y188100D03*
X1865100Y174600D03*
X1846517Y253500D03*
X1854720Y253700D03*
X1863137Y452710D03*
X1867500Y447900D03*
X1837857Y468630D03*
X1842857D03*
X1868167Y467855D03*
X1863000Y480000D03*
X1859600Y476200D03*
X1876945Y471316D03*
X1877407Y479046D03*
X1855206Y471112D03*
X1839126Y583354D03*
X1847070Y537610D03*
X1914690Y152580D03*
X1929736Y128337D03*
X1899855Y142122D03*
X1909216Y142812D03*
X1908327Y149353D03*
X1923800Y151000D03*
X1916310Y149676D03*
X1919514Y131701D03*
X1943660Y98180D03*
X1940500Y157600D03*
X1925400Y196300D03*
X1909438Y204307D03*
X1929700Y163400D03*
X1940240Y169970D03*
X1931065Y175520D03*
X1927500Y170400D03*
X1929000Y158600D03*
X1939400Y198400D03*
X1929090Y193190D03*
X1933100Y436200D03*
X1957063Y474769D03*
X1948200Y474300D03*
X1900890Y477200D03*
G54D52*
X57069Y147990D03*
X62560Y148940D03*
X69500Y388050D03*
X66809Y416405D03*
X60279Y415455D03*
X134000Y461350D03*
X139300Y453450D03*
X139776Y437704D03*
X121800Y462300D03*
X126700Y454400D03*
X130000Y446600D03*
X132100Y438654D03*
X427158Y122970D03*
X576115Y265575D03*
X1349730Y344550D03*
X1425443Y189960D03*
X1443930Y309840D03*
X1442169Y450250D03*
X1442646Y440250D03*
X1458100Y439300D03*
X1435500Y462230D03*
X1448000Y463180D03*
X1466800Y156800D03*
X1525567Y241237D03*
X1470768Y446550D03*
X1484200Y492420D03*
X1474488Y493370D03*
X1479303Y495800D03*
X1471829Y498585D03*
X1479300Y501438D03*
X1487200Y502388D03*
X1475483Y488050D03*
X1586771Y500628D03*
X1576075Y499693D03*
X1587815Y493308D03*
X1598477Y118900D03*
X1604603Y140607D03*
X1602600Y135856D03*
X1595851Y499678D03*
X1670733Y140300D03*
X1677740Y152650D03*
X1673132Y154625D03*
X1706296Y158650D03*
X1747300Y141050D03*
X1747654Y155850D03*
X1740779Y133050D03*
X1741419Y157650D03*
X1775900Y588400D03*
X1901671Y542000D03*
X1908295Y541050D03*
X1915085Y540100D03*
G54D136*
X1431595Y422663D03*
G54D128*
X1457000Y101300D03*
X1474100Y234400D03*
X1585849Y105088D03*
X1582849Y96088D03*
X1825700Y26300D03*
X1938600Y455317D03*
G54D71*
X47500Y507100D03*
X1471900Y176700D03*
X1599530Y205480D03*
X1627200Y169500D03*
X1669700Y85000D03*
X1745600Y87950D03*
X1759108Y132250D03*
Y127750D03*
Y141250D03*
Y136750D03*
X1767670Y132250D03*
Y127750D03*
Y141250D03*
Y136750D03*
X1759108Y145798D03*
X1767622D03*
X1725300Y198700D03*
X1891900Y225100D03*
G54D209*
X1923379Y78770D03*
X1918379D03*
X1928379D03*
X1933379D03*
Y105370D03*
X1918379D03*
X1923379D03*
X1928379D03*
G54D44*
X40200Y495721D03*
Y487879D03*
X36458D03*
X43942D03*
Y495721D03*
X36458D03*
G54D62*
X86750Y328000D03*
X102400Y313000D03*
X1615968Y23800D03*
G54D191*
X1836693Y120158D03*
X1954804D03*
G54D17*
X-17190Y471340D03*
Y474840D03*
X41542Y16578D03*
Y13078D03*
X44542Y16578D03*
Y13078D03*
X7600Y29800D03*
Y33300D03*
X41000Y271400D03*
Y267900D03*
X37000Y271400D03*
Y267900D03*
X46900Y298100D03*
Y294600D03*
X-8690Y460640D03*
Y464140D03*
X-13690Y460640D03*
Y464140D03*
X-5690Y473840D03*
Y470340D03*
X-8690Y473840D03*
Y470340D03*
X-500Y517500D03*
Y521000D03*
X-3500Y517500D03*
Y521000D03*
X31600Y517600D03*
Y521100D03*
X-12690Y481740D03*
Y478240D03*
X-9190Y481740D03*
Y478240D03*
X-12190Y471140D03*
Y467640D03*
X-2600Y538900D03*
Y542400D03*
X105700Y122000D03*
Y118500D03*
X102400D03*
Y122000D03*
X71500Y176500D03*
Y180000D03*
X75000Y176500D03*
Y180000D03*
X85500Y278500D03*
Y275000D03*
X80500Y278500D03*
Y275000D03*
X106600Y307000D03*
Y303500D03*
X69000Y341800D03*
X57000Y341500D03*
X91000Y317500D03*
Y321000D03*
X56000Y296200D03*
Y299700D03*
X94000Y307000D03*
Y303500D03*
X97500D03*
Y307000D03*
X89000Y309500D03*
Y306000D03*
X72000Y341800D03*
X101000Y303500D03*
Y307000D03*
X87500Y317500D03*
Y321000D03*
X69000Y292500D03*
Y289000D03*
X72500Y292500D03*
Y289000D03*
X69000Y345300D03*
X57000Y345000D03*
X75000Y372600D03*
Y376100D03*
X79500Y372600D03*
Y376100D03*
X72000Y345300D03*
X52601Y483087D03*
Y486587D03*
X106392Y534500D03*
Y531000D03*
X105392Y572300D03*
Y568800D03*
X105892Y612000D03*
Y608500D03*
X122000Y256500D03*
Y253000D03*
Y222900D03*
Y219400D03*
X122100Y287600D03*
Y284100D03*
Y320400D03*
Y316900D03*
X121800Y345800D03*
Y349300D03*
X121862Y377600D03*
Y381100D03*
X108892Y572300D03*
Y568800D03*
X112392Y572300D03*
Y568800D03*
X116892Y531000D03*
Y534500D03*
X115892Y568800D03*
Y572300D03*
X109892Y534500D03*
Y531000D03*
X113392Y534500D03*
Y531000D03*
X109392Y612000D03*
Y608500D03*
X112892Y612000D03*
Y608500D03*
X116392D03*
Y612000D03*
X195200Y382800D03*
Y386300D03*
X253000Y258600D03*
Y255100D03*
X249000Y258600D03*
Y255100D03*
X461000Y317303D03*
Y320803D03*
X510937Y262947D03*
Y266447D03*
X507400Y264496D03*
Y260996D03*
X514220Y263291D03*
Y266791D03*
X661800Y25500D03*
Y29000D03*
X656500Y-14000D03*
Y-17500D03*
X653150Y-14000D03*
Y-17500D03*
X650050Y-14300D03*
Y-17800D03*
X638500Y270500D03*
Y274000D03*
Y277000D03*
X663500Y254000D03*
Y257500D03*
X638488Y249513D03*
Y246013D03*
X646000Y261500D03*
Y265000D03*
X643823Y286894D03*
Y283394D03*
X639622Y286894D03*
Y283394D03*
X638500Y280500D03*
X654000Y342000D03*
X659000D03*
X649000D03*
X655500Y290000D03*
Y293500D03*
X658617Y288371D03*
Y291871D03*
X661767Y289974D03*
Y293474D03*
X654000Y345500D03*
X659000D03*
X649000D03*
X662000Y488500D03*
Y485000D03*
X636930Y488050D03*
Y484550D03*
X624700Y484100D03*
Y487600D03*
X632930Y484550D03*
Y488050D03*
X618430Y485050D03*
Y488550D03*
X614430Y485050D03*
Y488550D03*
X631600Y477600D03*
Y481100D03*
X614930Y481550D03*
Y478050D03*
X618430Y481550D03*
Y478050D03*
X713937Y-6048D03*
Y-9548D03*
X722937Y17452D03*
Y20952D03*
X719437Y17452D03*
Y20952D03*
X711233Y82298D03*
Y78798D03*
X707893Y82298D03*
Y78798D03*
X694000Y76000D03*
Y79500D03*
X716500Y53500D03*
Y50000D03*
X710500Y252500D03*
Y256000D03*
X673500Y291500D03*
Y295000D03*
X683000Y291300D03*
Y294800D03*
X684000Y342000D03*
X674000D03*
X679000D03*
X669000D03*
X722500Y283300D03*
Y286800D03*
X700500Y308000D03*
Y311500D03*
X664000Y342000D03*
X668500Y332500D03*
Y336000D03*
X684000Y345500D03*
X689000Y352500D03*
Y349000D03*
X693000Y352500D03*
Y349000D03*
X674000Y345500D03*
X679000D03*
X669000D03*
X664000D03*
X680500Y493000D03*
Y496500D03*
X673464Y503784D03*
Y507284D03*
X716000Y577500D03*
Y574000D03*
X722500Y577500D03*
Y574000D03*
X716400Y538800D03*
Y535300D03*
X728500Y283500D03*
Y287000D03*
X769600Y407600D03*
Y404100D03*
X766300Y407700D03*
Y404200D03*
X763200Y407700D03*
Y404200D03*
X765500Y568800D03*
Y572300D03*
X762000D03*
Y568800D03*
X759500Y534500D03*
Y531000D03*
X766500D03*
Y534500D03*
X763000D03*
Y531000D03*
X758500Y572300D03*
Y568800D03*
X755000Y572300D03*
Y568800D03*
X756000Y534500D03*
Y531000D03*
X759000Y612000D03*
Y608500D03*
X762500Y612000D03*
Y608500D03*
X766000D03*
Y612000D03*
X727000Y600500D03*
Y604000D03*
X755500Y612000D03*
Y608500D03*
X844808Y382800D03*
Y386300D03*
X899450Y258050D03*
Y254550D03*
X903050Y257950D03*
Y254450D03*
X1156980Y260920D03*
Y264420D03*
X1157013Y254048D03*
Y257548D03*
X1110300Y317800D03*
Y321300D03*
X1218254Y113956D03*
Y110456D03*
X1164900Y264826D03*
Y268326D03*
X1224924Y110448D03*
Y113948D03*
X1221682Y110456D03*
Y113956D03*
X1231442Y121275D03*
Y124775D03*
X1236600Y124877D03*
Y121377D03*
X1250890Y497310D03*
Y493810D03*
X1254390D03*
Y497310D03*
X1264700Y492143D03*
Y488643D03*
X1301500Y20000D03*
Y23500D03*
X1297000Y29500D03*
Y33000D03*
X1301100Y42600D03*
Y46100D03*
X1304500Y42600D03*
Y46100D03*
X1303697Y145379D03*
Y148879D03*
X1307197Y145379D03*
Y148879D03*
X1339889Y234171D03*
Y237671D03*
X1330800Y220450D03*
Y223950D03*
X1334389Y234171D03*
Y237671D03*
X1312389Y234171D03*
Y237671D03*
X1317889Y234171D03*
Y237671D03*
X1323389Y234171D03*
Y237671D03*
X1328889Y234171D03*
Y237671D03*
X1334389D03*
Y241171D03*
X1339889Y237671D03*
Y241171D03*
X1317889Y237671D03*
Y241171D03*
X1323389Y237671D03*
Y241171D03*
X1328889Y237671D03*
Y241171D03*
X1312389Y237671D03*
Y241171D03*
X1339800Y336800D03*
Y340300D03*
X1322430Y337460D03*
Y333960D03*
X1327400Y333930D03*
Y337430D03*
X1339240Y309384D03*
Y305884D03*
Y302384D03*
Y305884D03*
X1333740Y309384D03*
Y305884D03*
Y302384D03*
Y305884D03*
X1339800Y346800D03*
Y343300D03*
X1337600Y442100D03*
Y438600D03*
X1375500Y68500D03*
Y65000D03*
X1376500Y113600D03*
Y110100D03*
X1394889Y234171D03*
Y237671D03*
X1378389Y234171D03*
Y237671D03*
X1367389Y234171D03*
Y237671D03*
X1372889Y234171D03*
Y237671D03*
X1361889Y234171D03*
Y237671D03*
X1356389Y234171D03*
Y237671D03*
X1389389Y234171D03*
Y237671D03*
X1350889Y234171D03*
Y237671D03*
X1345389Y234171D03*
Y237671D03*
X1383889Y234171D03*
Y237671D03*
X1394889D03*
Y241171D03*
X1350889Y237671D03*
Y241171D03*
X1389389Y237671D03*
Y241171D03*
X1383889Y237671D03*
Y241171D03*
X1378389Y237671D03*
Y241171D03*
X1367389Y237671D03*
Y241171D03*
X1372889Y237671D03*
Y241171D03*
X1361889Y237671D03*
Y241171D03*
X1356389Y237671D03*
Y241171D03*
X1345389Y237671D03*
Y241171D03*
X1357000Y329000D03*
Y325500D03*
X1353500D03*
Y329000D03*
X1395135Y310254D03*
Y306754D03*
Y303254D03*
Y306754D03*
X1400537Y310254D03*
Y306754D03*
Y303254D03*
Y306754D03*
X1371000Y325400D03*
Y328900D03*
X1374500Y325400D03*
Y328900D03*
X1350000Y325500D03*
Y329000D03*
X1361544Y309384D03*
Y305884D03*
X1356044Y302384D03*
Y305884D03*
X1361544Y302384D03*
Y305884D03*
X1383548Y309934D03*
Y306434D03*
X1389635Y303254D03*
Y306754D03*
X1383548Y302934D03*
Y306434D03*
X1389635Y310254D03*
Y306754D03*
X1378048Y302934D03*
Y306434D03*
Y309934D03*
Y306434D03*
X1345142Y309384D03*
Y305884D03*
X1350642Y309384D03*
Y305884D03*
X1345142Y302384D03*
Y305884D03*
X1350642Y302384D03*
Y305884D03*
X1366840Y302754D03*
Y306254D03*
X1372340Y302754D03*
Y306254D03*
X1366840Y309754D03*
Y306254D03*
X1372340Y309754D03*
Y306254D03*
X1356044Y309384D03*
Y305884D03*
X1396052Y357720D03*
Y354220D03*
X1391212Y357760D03*
Y354260D03*
X1348988Y355077D03*
Y351577D03*
X1387500Y423600D03*
Y427100D03*
X1371500Y526000D03*
Y529500D03*
X1379100Y578000D03*
Y574500D03*
X1379200Y609300D03*
Y605800D03*
X1455100Y24550D03*
Y21050D03*
X1451600Y24550D03*
Y21050D03*
X1464500Y20750D03*
Y24250D03*
X1448600Y24550D03*
Y21050D03*
X1416800Y16700D03*
Y20200D03*
X1413800Y16700D03*
Y20200D03*
X1410800Y16700D03*
Y20200D03*
X1457000Y108500D03*
Y112000D03*
X1445500Y153300D03*
Y156800D03*
X1447391Y142729D03*
Y139229D03*
X1447428Y145543D03*
Y149043D03*
X1463900Y205550D03*
Y202050D03*
X1465234Y183258D03*
Y186758D03*
X1462059Y191683D03*
Y188183D03*
X1426261Y176309D03*
Y179809D03*
Y163309D03*
Y166809D03*
X1445500Y163300D03*
Y159800D03*
X1426261Y169809D03*
Y173309D03*
Y186309D03*
Y182809D03*
X1438500Y163300D03*
Y159800D03*
X1442000Y163300D03*
Y159800D03*
X1464500Y262100D03*
Y258600D03*
X1454500Y251250D03*
Y247750D03*
X1458500Y249000D03*
Y245500D03*
X1443000Y248750D03*
Y245250D03*
X1446000Y248750D03*
Y245250D03*
X1440000Y248750D03*
Y245250D03*
X1458011Y264408D03*
Y267908D03*
X1460835Y261026D03*
Y257526D03*
X1457835D03*
Y261026D03*
X1430900Y250350D03*
Y246850D03*
X1406037Y303254D03*
Y306754D03*
X1411220Y310284D03*
Y306784D03*
X1416720Y310284D03*
Y306784D03*
Y303284D03*
Y306784D03*
X1411220Y303284D03*
Y306784D03*
X1406037Y310254D03*
Y306754D03*
X1460868Y373393D03*
Y369893D03*
X1425600Y523700D03*
X1422000D03*
X1416600Y524500D03*
X1460600Y521100D03*
Y517600D03*
X1425600Y527200D03*
X1422000D03*
X1416600Y528000D03*
X1460500Y537500D03*
Y534000D03*
X1468000Y20750D03*
Y24250D03*
X1471500Y20750D03*
Y24250D03*
X1505500Y9641D03*
Y6141D03*
X1502300Y9641D03*
Y6141D03*
X1487000Y83500D03*
Y80000D03*
Y73500D03*
Y77000D03*
X1520904Y51355D03*
Y47855D03*
X1486193Y103797D03*
Y107297D03*
X1485150Y148500D03*
Y145000D03*
X1466188Y171277D03*
Y167777D03*
X1471988Y166677D03*
Y170177D03*
X1467992Y205635D03*
Y202135D03*
X1480988Y166677D03*
Y170177D03*
X1477988Y166677D03*
Y170177D03*
X1474988Y166677D03*
Y170177D03*
X1484100Y177700D03*
Y174200D03*
X1493700Y185400D03*
Y181900D03*
X1487230Y261150D03*
Y264650D03*
X1490310Y261140D03*
Y264640D03*
X1478000Y263500D03*
Y260000D03*
X1484000Y263500D03*
Y260000D03*
X1481000D03*
Y263500D03*
X1493450Y261140D03*
Y264640D03*
X1472000Y260000D03*
Y263500D03*
X1475000D03*
Y260000D03*
X1477500Y219350D03*
Y222850D03*
X1476800Y231000D03*
Y227500D03*
X1470554Y236923D03*
Y233423D03*
X1478424Y241688D03*
Y245188D03*
X1467054Y236923D03*
Y233423D03*
X1518952Y337082D03*
Y333582D03*
X1521952Y337082D03*
Y333582D03*
X1490500Y336000D03*
Y339500D03*
X1502850Y336900D03*
Y333400D03*
X1515952Y337082D03*
Y333582D03*
X1512952Y337082D03*
Y333582D03*
X1490000Y332100D03*
Y328600D03*
X1523000Y347250D03*
Y343750D03*
X1520000Y347250D03*
Y343750D03*
X1526000Y347250D03*
Y343750D03*
X1466967Y353465D03*
Y349965D03*
X1477500Y348750D03*
Y352250D03*
X1474049Y350889D03*
Y347389D03*
X1499000Y347250D03*
Y343750D03*
X1496000Y347250D03*
Y343750D03*
X1493000Y347250D03*
Y343750D03*
X1481000Y343250D03*
Y346750D03*
X1494023Y361853D03*
Y358353D03*
X1475500Y358750D03*
Y355250D03*
X1505000Y347250D03*
Y343750D03*
X1502000Y347250D03*
Y343750D03*
X1481164Y359387D03*
Y362887D03*
X1517000Y346650D03*
Y343150D03*
X1502800Y356420D03*
Y359920D03*
X1470467Y349965D03*
Y353465D03*
X1486572Y432791D03*
Y436291D03*
X1506800Y454500D03*
Y451000D03*
X1479150Y430678D03*
Y434178D03*
X1522870Y503200D03*
Y499700D03*
X1525700Y515310D03*
Y511810D03*
X1483700Y521700D03*
Y518200D03*
X1476600Y523100D03*
Y519600D03*
X1478000Y527250D03*
Y530750D03*
X1483200Y537200D03*
Y533700D03*
X1494800Y536700D03*
Y540200D03*
X1472300Y608439D03*
Y611939D03*
X1507952Y608439D03*
Y611939D03*
X1549000Y74450D03*
Y77950D03*
X1562909Y64718D03*
Y68218D03*
X1559909Y64718D03*
Y68218D03*
X1544814Y77485D03*
Y80985D03*
X1551050Y39445D03*
Y42945D03*
X1548050Y39445D03*
Y42945D03*
X1577431Y90987D03*
Y87487D03*
X1586149Y94288D03*
X1557277Y49563D03*
Y46063D03*
X1580531Y87500D03*
Y91000D03*
X1588000Y138500D03*
Y142000D03*
X1579167Y107718D03*
Y104218D03*
X1568000Y111500D03*
Y108000D03*
X1565500Y152500D03*
Y149000D03*
X1562500Y152500D03*
Y149000D03*
X1547400Y149700D03*
Y146200D03*
X1561709Y124081D03*
Y120581D03*
X1552171Y130471D03*
Y126971D03*
X1566481Y127454D03*
Y130954D03*
X1582649Y103288D03*
Y106788D03*
X1586149Y97788D03*
X1551858Y98991D03*
Y102491D03*
X1576414Y117787D03*
Y121287D03*
X1588156Y125638D03*
Y129138D03*
X1576040Y210090D03*
Y213590D03*
X1574500Y217000D03*
X1579540Y210090D03*
Y213590D03*
X1583190Y210070D03*
Y213570D03*
X1574500Y220500D03*
Y223500D03*
Y227000D03*
X1535966Y337018D03*
Y333518D03*
X1539000Y337000D03*
Y333500D03*
X1582000Y292500D03*
Y289000D03*
X1585000Y292500D03*
Y289000D03*
X1539000Y340750D03*
X1556500Y334750D03*
Y338250D03*
X1553500Y334750D03*
Y338250D03*
X1545000Y340750D03*
X1563000Y338250D03*
Y334750D03*
X1566000Y338250D03*
Y334750D03*
X1542000Y340750D03*
X1536000D03*
X1533000D03*
X1584000Y347250D03*
Y343750D03*
X1581000Y347250D03*
Y343750D03*
X1539000Y344250D03*
X1553500Y343750D03*
Y347250D03*
X1556500Y343750D03*
Y347250D03*
X1559500D03*
Y343750D03*
X1545000Y344250D03*
X1529000Y347250D03*
Y343750D03*
X1542000Y344250D03*
X1536000D03*
X1533000D03*
X1562500Y347300D03*
Y343800D03*
X1565500D03*
Y347300D03*
X1568600Y344050D03*
Y347550D03*
X1571800Y347800D03*
Y344300D03*
X1579000Y413250D03*
Y409750D03*
X1579500Y425250D03*
Y421750D03*
X1546596Y441697D03*
Y445197D03*
X1545271Y419162D03*
Y422662D03*
X1573877Y451641D03*
Y455141D03*
X1577782Y451536D03*
Y455036D03*
Y461336D03*
Y457836D03*
X1574377Y457941D03*
Y461441D03*
X1575500Y435000D03*
Y438500D03*
X1586670Y463250D03*
X1528100Y443350D03*
Y446850D03*
X1528500Y420500D03*
Y417000D03*
X1529000Y515310D03*
Y511810D03*
X1588300Y487500D03*
Y484000D03*
X1586670Y466750D03*
X1584500Y586600D03*
Y583100D03*
X1537700Y610897D03*
Y607397D03*
X1644000Y22250D03*
Y25750D03*
Y28750D03*
Y32250D03*
X1613000Y-14218D03*
Y-10718D03*
X1621500Y32750D03*
Y29250D03*
Y22250D03*
Y25750D03*
X1606500Y30750D03*
Y27250D03*
Y20750D03*
Y17250D03*
X1592453Y6002D03*
Y2502D03*
X1641600Y84000D03*
Y87500D03*
Y94000D03*
Y90500D03*
X1602000Y87250D03*
Y90750D03*
X1603800Y54950D03*
Y51450D03*
X1638500Y84000D03*
Y87500D03*
Y94000D03*
Y90500D03*
X1600300Y57950D03*
Y54450D03*
X1641600Y99000D03*
Y102500D03*
X1596865Y145871D03*
Y149371D03*
X1590949Y104288D03*
Y100788D03*
X1597349D03*
Y104288D03*
X1604400Y119300D03*
Y115800D03*
X1604939Y132088D03*
Y128588D03*
X1601400Y113100D03*
Y116600D03*
X1648500Y141750D03*
Y138250D03*
X1644930Y153700D03*
X1641274Y130773D03*
Y127273D03*
X1638500Y99000D03*
Y102500D03*
X1648500Y128750D03*
Y125250D03*
X1632050Y145170D03*
Y148670D03*
X1594149Y100788D03*
Y104288D03*
X1635000Y125750D03*
Y122250D03*
X1648500Y131750D03*
Y135250D03*
X1626900Y144300D03*
Y147800D03*
X1591356Y125638D03*
Y129138D03*
X1639649Y179288D03*
Y175788D03*
X1642649Y179288D03*
Y175788D03*
X1648349D03*
Y179288D03*
X1636649D03*
Y175788D03*
X1625000Y177808D03*
Y181308D03*
X1610500Y188500D03*
Y192000D03*
X1618940Y175780D03*
Y179280D03*
X1616500Y188500D03*
Y192000D03*
X1613500Y188500D03*
Y192000D03*
X1644930Y157200D03*
X1605760Y224590D03*
Y221090D03*
X1650473Y319500D03*
Y323000D03*
X1644300Y288050D03*
Y291550D03*
X1647300Y288050D03*
Y291550D03*
X1626217Y360391D03*
Y363891D03*
X1626100Y373700D03*
Y370200D03*
X1602700Y466900D03*
Y470400D03*
X1611175Y477667D03*
Y481167D03*
X1645256Y558000D03*
Y554500D03*
X1641756D03*
Y558000D03*
X1665000Y26250D03*
Y29750D03*
Y23250D03*
Y19750D03*
X1662600Y49000D03*
Y52500D03*
X1676400Y69500D03*
Y66000D03*
X1691800Y88700D03*
Y92200D03*
X1694800D03*
Y88700D03*
X1697800Y92200D03*
Y88700D03*
X1700800D03*
Y92200D03*
X1656000Y94500D03*
Y91000D03*
Y84500D03*
Y88000D03*
X1672500Y109800D03*
Y106300D03*
X1656000Y97500D03*
Y101000D03*
X1653849Y175788D03*
Y179288D03*
X1666701Y176011D03*
Y179511D03*
X1670081Y164849D03*
Y161349D03*
X1663681Y164849D03*
Y161349D03*
X1666881Y164849D03*
Y161349D03*
X1659500Y317250D03*
Y320750D03*
X1651500Y291650D03*
Y288150D03*
X1661248Y308711D03*
Y305211D03*
X1656000Y324250D03*
Y320750D03*
X1663280Y287691D03*
Y291191D03*
X1660080Y287691D03*
Y291191D03*
X1710101Y558628D03*
Y555128D03*
X1680000Y555900D03*
Y559400D03*
X1674000Y555500D03*
Y559000D03*
X1670000Y555500D03*
Y559000D03*
X1663000Y555400D03*
Y558900D03*
X1659500Y555400D03*
Y558900D03*
X1684000Y555900D03*
Y559400D03*
X1773100Y15200D03*
Y18700D03*
X1769250Y81070D03*
Y84570D03*
X1762300Y51600D03*
Y48100D03*
X1740300Y92100D03*
X1752060Y92110D03*
X1749810Y85620D03*
Y82120D03*
X1748550Y148138D03*
Y144638D03*
X1754825Y113100D03*
Y116600D03*
X1733403Y130212D03*
Y126712D03*
X1748425Y113100D03*
Y116600D03*
X1751625Y113100D03*
Y116600D03*
X1758025Y113100D03*
Y116600D03*
X1740300Y95600D03*
X1752060Y95610D03*
X1771525Y202827D03*
Y206327D03*
X1759497Y202827D03*
Y206327D03*
X1763497Y202827D03*
Y206327D03*
X1734100Y202400D03*
Y205900D03*
X1726000Y202750D03*
Y206250D03*
X1722500Y202750D03*
Y206250D03*
X1719000Y202750D03*
Y206250D03*
X1729500Y202750D03*
Y206250D03*
X1737600Y202400D03*
Y205900D03*
X1750589Y202571D03*
Y206071D03*
X1746589Y202571D03*
Y206071D03*
X1757220Y258433D03*
Y254933D03*
X1760420Y258433D03*
Y254933D03*
X1753900Y258400D03*
Y254900D03*
X1747500Y258400D03*
Y254900D03*
X1744300Y258400D03*
Y254900D03*
X1750700Y258400D03*
Y254900D03*
X1760000Y455130D03*
Y458630D03*
X1768500Y455130D03*
Y458630D03*
X1772500Y455130D03*
Y458630D03*
X1743500Y455130D03*
Y458630D03*
X1747500Y455130D03*
Y458630D03*
X1756000Y455130D03*
Y458630D03*
X1764900Y512800D03*
Y509300D03*
X1768400Y512800D03*
Y509300D03*
X1730950Y586000D03*
Y582500D03*
X1733950Y586004D03*
Y582504D03*
X1726850Y559000D03*
Y555500D03*
X1723000Y559000D03*
Y555500D03*
X1714101Y558628D03*
Y555128D03*
X1729950Y559000D03*
Y555500D03*
X1720550Y586250D03*
X1765000Y579000D03*
Y582500D03*
X1736097Y596859D03*
Y593359D03*
X1757057Y598292D03*
Y601792D03*
X1720550Y589750D03*
X1760157Y598243D03*
Y601743D03*
X1822400Y24700D03*
Y28200D03*
X1825500Y14250D03*
Y17750D03*
X1833236Y32980D03*
Y29480D03*
X1829236Y32980D03*
Y29480D03*
X1821250Y94500D03*
Y91000D03*
X1786700Y81450D03*
Y77950D03*
X1795377Y126231D03*
Y122731D03*
X1798377D03*
Y126231D03*
X1780623Y113769D03*
Y117269D03*
X1789300Y171000D03*
Y167500D03*
X1826100Y202927D03*
Y206427D03*
X1822100Y202927D03*
Y206427D03*
X1775525Y202827D03*
Y206327D03*
X1788300Y202527D03*
Y206027D03*
X1797200Y203127D03*
Y206627D03*
X1801200Y203127D03*
Y206627D03*
X1809600Y203027D03*
Y206527D03*
X1813600Y203027D03*
Y206527D03*
X1784300Y202527D03*
Y206027D03*
X1823000Y455130D03*
Y458630D03*
X1836000Y455130D03*
Y458630D03*
X1832000Y455130D03*
Y458630D03*
X1819000Y455130D03*
Y458630D03*
X1806500Y455130D03*
Y458630D03*
X1810500Y455130D03*
Y458630D03*
X1781500Y455130D03*
Y458630D03*
X1798000Y455130D03*
Y458630D03*
X1794000Y455130D03*
Y458630D03*
X1785500Y455130D03*
Y458630D03*
X1825000Y507200D03*
Y503700D03*
X1779300Y519100D03*
Y515600D03*
X1817900Y495600D03*
Y499100D03*
X1814400Y495600D03*
Y499100D03*
X1779300Y508100D03*
Y511600D03*
X1828600Y532500D03*
Y529000D03*
X1822052Y569001D03*
Y572501D03*
X1833052Y575501D03*
Y579001D03*
Y586001D03*
Y582501D03*
X1802400Y559100D03*
Y562600D03*
X1798400Y559100D03*
Y562600D03*
X1789188Y565224D03*
Y568724D03*
X1825552Y569001D03*
Y572501D03*
X1798250Y535300D03*
Y531800D03*
X1790500Y555600D03*
Y559100D03*
X1782700Y608400D03*
Y604900D03*
X1785700Y608400D03*
Y604900D03*
X1842000Y13750D03*
Y17250D03*
X1886465Y-15068D03*
Y-18568D03*
X1844835Y20168D03*
Y23668D03*
X1889575Y-15062D03*
Y-18562D03*
X1843236Y41480D03*
Y37980D03*
X1847236Y41480D03*
Y37980D03*
Y41480D03*
Y44980D03*
X1843236Y41480D03*
Y44980D03*
X1853600Y56800D03*
Y60300D03*
X1870817Y64594D03*
Y61094D03*
X1881290Y112580D03*
Y109080D03*
X1897500Y131500D03*
Y128000D03*
X1881000Y130750D03*
Y134250D03*
X1877500Y130750D03*
Y134250D03*
X1874939Y112567D03*
Y109067D03*
X1889790Y112580D03*
Y109080D03*
X1886290Y112580D03*
Y109080D03*
X1889913Y216937D03*
X1839000Y187250D03*
Y183750D03*
X1842000Y187250D03*
Y183750D03*
X1845000Y187250D03*
Y183750D03*
X1889913Y210437D03*
Y213937D03*
Y220437D03*
X1853000Y463500D03*
Y460000D03*
X1856000Y463500D03*
Y460000D03*
X1846000Y506000D03*
Y502500D03*
X1867500Y472200D03*
Y475700D03*
X1846000Y499500D03*
Y496000D03*
X1849000Y499500D03*
Y496000D03*
X1881293Y519486D03*
Y522986D03*
X1878272Y519465D03*
Y522965D03*
X1858090Y508600D03*
Y512100D03*
X1854890Y508600D03*
Y512100D03*
X1880704Y572718D03*
Y576218D03*
X1877704D03*
Y572718D03*
X1868704Y576218D03*
Y572718D03*
X1871704Y576218D03*
Y572718D03*
X1874704D03*
Y576218D03*
X1925135Y111900D03*
Y115400D03*
X1921620Y111900D03*
Y115400D03*
X1917953D03*
Y111900D03*
X1940900Y153400D03*
Y149900D03*
X1908100Y155900D03*
X1925535Y136078D03*
Y132578D03*
X1916300Y156300D03*
X1901000Y131500D03*
Y128000D03*
X1947686Y190522D03*
Y187022D03*
X1943482Y166512D03*
Y163012D03*
X1947646Y178328D03*
Y181828D03*
X1947662Y171828D03*
Y175328D03*
X1932700Y206835D03*
Y203335D03*
X1958902Y159545D03*
Y163045D03*
X1943776Y173012D03*
Y169512D03*
X1947686Y197022D03*
Y193522D03*
X1905800Y187550D03*
Y191050D03*
X1908100Y159400D03*
X1916300Y159800D03*
X1934800Y457700D03*
Y454200D03*
X1904000Y441630D03*
Y445130D03*
X1949940Y491950D03*
Y488450D03*
X1946350Y491950D03*
Y488450D03*
X1953440Y491950D03*
Y488450D03*
X1912800Y508250D03*
Y504750D03*
X1909800Y508250D03*
Y504750D03*
X1943100Y491920D03*
Y488420D03*
X1934720Y520400D03*
Y523900D03*
X1954120Y510380D03*
Y513880D03*
X1923260Y482920D03*
Y486420D03*
X1950620Y510380D03*
Y513880D03*
X1908859Y481161D03*
Y477661D03*
X1952970Y501030D03*
Y504530D03*
X1949800Y545850D03*
Y542350D03*
X1946800Y545900D03*
Y542400D03*
X1899550Y586365D03*
Y582865D03*
X1899700Y591100D03*
Y594600D03*
X1969100Y551100D03*
Y554600D03*
X1969800Y574600D03*
Y578100D03*
X1965700Y578200D03*
Y574700D03*
X1966100Y551000D03*
Y554500D03*
X1963200Y594600D03*
Y598100D03*
X1970000Y598200D03*
Y594700D03*
G54D155*
X1646200Y92500D03*
Y87500D03*
X1618700Y90800D03*
X1646200Y97500D03*
G54D26*
X42800Y35300D03*
Y56300D03*
Y77300D03*
X43100Y568100D03*
X42900Y547900D03*
X43100Y588600D03*
Y608600D03*
X70800Y35300D03*
Y56300D03*
Y77300D03*
X71100Y568100D03*
X70900Y547900D03*
X71100Y588600D03*
Y608600D03*
X150000Y267500D03*
Y246500D03*
Y224500D03*
Y288500D03*
Y310500D03*
Y330500D03*
X151574Y396363D03*
X150000Y352000D03*
X151574Y376363D03*
X178000Y267500D03*
Y246500D03*
Y224500D03*
Y288500D03*
Y310500D03*
Y330500D03*
X179574Y396363D03*
X178000Y352000D03*
X179574Y376363D03*
X568500Y483500D03*
X596500D03*
X649500Y217500D03*
Y238800D03*
X667900Y562300D03*
X730000Y195700D03*
X677500Y217500D03*
Y238800D03*
X695900Y562300D03*
X758000Y195700D03*
X802108Y246500D03*
X830108D03*
X802108Y224500D03*
X830108D03*
X802108Y267500D03*
X830108D03*
X802108Y310500D03*
X830108D03*
X802108Y288500D03*
X830108D03*
X802108Y330500D03*
X830108D03*
X801182Y376363D03*
X829182D03*
X801182Y396363D03*
X829182D03*
X802108Y352800D03*
X830108D03*
X1343000Y-8000D03*
X1315000D03*
X1343000Y13000D03*
X1315000D03*
X1323000Y371000D03*
Y391000D03*
X1347600Y431000D03*
X1323000Y411000D03*
X1339081Y473466D03*
X1311081D03*
X1340172Y491683D03*
X1312172D03*
X1343000Y592000D03*
X1315000D03*
X1335500Y556500D03*
X1307500D03*
X1334300Y533100D03*
X1306300D03*
X1343000Y612000D03*
X1315000D03*
X1356000Y137000D03*
X1384000D03*
X1377700Y183700D03*
X1349700D03*
X1351000Y371000D03*
Y391000D03*
X1375600Y431000D03*
X1351000Y411000D03*
X1871725Y87256D03*
X1899725D03*
X1897200Y463700D03*
X1925200D03*
G54D173*
X1681717Y116349D03*
G54D80*
X476672Y220096D03*
Y235696D03*
X483432Y216196D03*
X480052Y210346D03*
X483432Y212296D03*
X531871Y202547D03*
X525111D03*
X483432Y231797D03*
X480052Y225947D03*
X483432Y239596D03*
X501452Y337096D03*
X538631Y331247D03*
Y327347D03*
X535251Y340996D03*
Y337096D03*
X528491Y340996D03*
X531871Y339047D03*
Y331247D03*
X538631Y323446D03*
X525111Y319547D03*
X518352Y335147D03*
X521731Y333196D03*
Y329296D03*
X525111Y331247D03*
X528491Y333196D03*
X521731Y340996D03*
X525111Y323446D03*
X528491Y325396D03*
Y329296D03*
Y321496D03*
X531871Y323446D03*
X525111Y327347D03*
X521731Y337096D03*
X487932Y356596D03*
X491312Y342947D03*
Y354647D03*
X511592Y389747D03*
Y401447D03*
X508212Y383896D03*
X504832Y401446D03*
X535251Y348796D03*
Y344896D03*
X538631Y346847D03*
Y342947D03*
X535251Y360496D03*
X531871Y358547D03*
X535251Y364396D03*
Y368296D03*
X525111Y346847D03*
X528491Y348796D03*
X531871Y342947D03*
X528491Y344896D03*
Y352696D03*
X538631Y354647D03*
Y358547D03*
Y362447D03*
X531871D03*
Y366347D03*
X535251Y372197D03*
X538631Y350747D03*
X535251Y379996D03*
X538631Y374146D03*
X531871Y378047D03*
X514972Y376096D03*
X528491Y387796D03*
X521731D03*
Y391696D03*
X518352Y393647D03*
X514972Y395597D03*
X528491Y379996D03*
Y383896D03*
X525111Y385847D03*
X521731Y383896D03*
X525111Y389747D03*
X521731Y395597D03*
X514972Y391696D03*
Y387796D03*
X528491Y376096D03*
X531871Y381947D03*
X494692Y387796D03*
X514972Y364396D03*
X518352Y350747D03*
X504832Y374146D03*
X508212Y368296D03*
X514972Y360496D03*
X508212Y372197D03*
X511592Y354647D03*
X498072Y378047D03*
Y381947D03*
X518352Y354647D03*
X511592Y366347D03*
X494692Y379996D03*
X501452Y376096D03*
X511592Y362447D03*
X508212Y364396D03*
X514972Y368296D03*
X511592Y358547D03*
X498072Y374146D03*
X521731Y352696D03*
X494692Y383896D03*
X518352Y346847D03*
X484552Y374146D03*
X487932Y383896D03*
X491312Y393647D03*
X494692Y399496D03*
X484552Y389747D03*
X552151Y331247D03*
Y335147D03*
X548771Y333196D03*
X552151Y339047D03*
X555531Y340996D03*
X542011D03*
Y337096D03*
X545391Y327347D03*
Y339047D03*
X542011Y333196D03*
Y329296D03*
Y325396D03*
X562591Y340996D03*
X558911Y339047D03*
X562591Y337096D03*
X555531D03*
X552151Y342947D03*
X548771Y344896D03*
X552151Y346847D03*
X542011Y344896D03*
Y356596D03*
X559211Y366347D03*
X558911Y354647D03*
X552151Y362447D03*
X545391Y350747D03*
X548771Y348796D03*
X555531Y352696D03*
Y348796D03*
X552151Y354647D03*
X558911Y350747D03*
X555531Y344896D03*
X548771Y387796D03*
X552151Y385847D03*
X555531Y379996D03*
X552151Y381947D03*
X937747Y322209D03*
X930987D03*
X947887Y324160D03*
X941127D03*
G54D164*
X1638131Y525946D03*
Y475946D03*
G54D53*
X63093Y202300D03*
X72936D03*
X82779D03*
X1628142Y240199D03*
Y263999D03*
X1892720Y525415D03*
X1914911Y495775D03*
X1934597D03*
X1924754D03*
X1900595Y525415D03*
X1908469D03*
X1916343D03*
X1924217D03*
X1922248Y518328D03*
X1912406D03*
X1904532D03*
G54D182*
X1724606Y235430D03*
X1930319Y451179D03*
G54D35*
X48700Y261300D03*
X29000D03*
X48700Y250260D03*
X29000D03*
G54D119*
X1401516Y23976D03*
X1392264D03*
X1504666Y29882D03*
X1513918Y23976D03*
G54D218*
X1928842Y222302D03*
X1930810D03*
X1934747D03*
X1936716D03*
X1928842Y220003D03*
X1930810D03*
X1934747D03*
X1936716D03*
G54D137*
X1458271Y446520D03*
G54D146*
X1508500Y432500D03*
X1513400D03*
G54D156*
X1624249Y156438D03*
X1680200Y165650D03*
X1780103Y69879D03*
X1833650Y98250D03*
G54D81*
X503389Y136125D03*
G54D219*
X1932779Y221153D03*
G54D54*
X75500Y279500D03*
Y274000D03*
X51200Y496250D03*
Y490750D03*
X194600Y242848D03*
Y248348D03*
Y238348D03*
Y232848D03*
Y274000D03*
Y279500D03*
Y303000D03*
Y308500D03*
Y335730D03*
Y341230D03*
Y363600D03*
Y369100D03*
X454148Y299091D03*
Y304591D03*
Y288341D03*
Y282841D03*
X714950Y12050D03*
Y17550D03*
X723135Y4952D03*
Y-548D03*
X680600Y42300D03*
Y47800D03*
X667500Y294800D03*
Y289300D03*
X679800Y528500D03*
Y534000D03*
X717203Y588502D03*
X712101Y588262D03*
X717203Y594002D03*
X712101Y593762D03*
X729335Y4952D03*
Y-548D03*
X729350Y506700D03*
Y501200D03*
X844500Y238480D03*
Y232980D03*
Y242980D03*
Y248480D03*
Y271500D03*
Y277000D03*
Y303200D03*
Y308700D03*
Y334750D03*
Y340250D03*
Y366300D03*
Y371800D03*
X1103756Y299091D03*
Y304591D03*
Y288341D03*
Y282841D03*
X1338500Y101500D03*
Y107000D03*
X1335900Y512800D03*
Y518300D03*
X1304500Y619000D03*
Y613500D03*
X1528100Y426600D03*
Y432100D03*
X1472500Y538250D03*
Y543750D03*
X1477500Y538250D03*
Y543750D03*
X1499400Y536000D03*
Y541500D03*
X1514600Y536000D03*
Y541500D03*
X1509600Y536000D03*
Y541500D03*
X1504300Y536000D03*
Y541500D03*
X1585064Y122049D03*
Y116549D03*
X1576187Y131439D03*
Y136939D03*
X1583500Y127000D03*
Y132500D03*
X1580364Y116549D03*
Y122049D03*
X1580000Y399350D03*
X1575300D03*
X1580000Y404850D03*
X1579814Y434014D03*
Y439514D03*
X1575300Y404850D03*
X1575500Y431000D03*
Y425500D03*
X1571584Y561509D03*
Y556009D03*
X1576520Y561500D03*
Y556000D03*
X1632849Y134888D03*
Y140388D03*
X1609300Y403200D03*
X1604000Y403250D03*
X1590700Y465250D03*
Y459750D03*
X1608000Y464546D03*
X1595500Y465250D03*
Y459750D03*
X1590600Y422250D03*
Y416750D03*
X1600000Y422250D03*
Y416750D03*
X1609300Y408700D03*
X1604000Y408750D03*
X1595300Y422250D03*
Y416750D03*
X1608000Y470046D03*
X1674031Y166649D03*
Y161149D03*
X1828090Y156630D03*
X1833650Y156830D03*
X1828090Y162130D03*
X1833650Y162330D03*
X1869490Y112980D03*
Y107480D03*
X1895137Y105252D03*
Y110752D03*
X1843600Y158200D03*
Y163700D03*
X1901400Y156850D03*
Y151350D03*
X1912100Y156400D03*
X1910500Y185750D03*
Y191250D03*
X1912100Y161900D03*
G54D165*
X1611283Y567874D03*
Y615236D03*
X1658528Y567874D03*
X1705772D03*
Y615236D03*
G54D192*
X1830800Y513800D03*
Y503300D03*
X1834540Y513800D03*
X1838280D03*
Y503300D03*
G54D90*
X586109Y367405D03*
G54D63*
X68418Y325500D03*
X65859D03*
X68418Y332500D03*
X63300D03*
X65859D03*
X63300Y325500D03*
X663000Y507500D03*
Y500500D03*
X668118D03*
X665559Y507500D03*
X668118D03*
X1231394Y116162D03*
X1233953D03*
X1228835D03*
Y109162D03*
X1231394D03*
X1233953D03*
X1241772Y109188D03*
X1239213D03*
X1244331D03*
Y116188D03*
X1241772D03*
X1239213D03*
X1306320Y28900D03*
X1303760D03*
X1301200D03*
X1306320Y35900D03*
X1301200D03*
X1303760D03*
X1596082Y219000D03*
X1598641D03*
X1596082Y212000D03*
X1601200D03*
X1598641D03*
X1601200Y219000D03*
X1759067Y586743D03*
X1753949D03*
X1756508Y593743D03*
X1759067D03*
X1753949D03*
X1795436Y131481D03*
X1792877Y138481D03*
X1790318Y131481D03*
X1795436Y138481D03*
X1790318D03*
X1789300Y506600D03*
X1784182Y513600D03*
X1786741Y506600D03*
X1789300Y513600D03*
X1784182Y506600D03*
X1812800Y510600D03*
X1817918Y503600D03*
X1815359Y510600D03*
X1812800Y503600D03*
X1817918Y510600D03*
X1804541D03*
X1807100D03*
X1804541Y503600D03*
X1807100D03*
X1801982D03*
Y510600D03*
X1894968Y213827D03*
Y220827D03*
X1897527D03*
X1900086Y213827D03*
X1936369Y190204D03*
X1938928D03*
X1936369Y183204D03*
X1941487D03*
X1938928D03*
X1941487Y190204D03*
X1900086Y220827D03*
X1943518Y517500D03*
X1938400Y524500D03*
X1940959D03*
X1938400Y517500D03*
X1943518Y524500D03*
X1942722Y505100D03*
X1945281Y498100D03*
X1947840D03*
Y505100D03*
X1942722Y498100D03*
X1951439Y519250D03*
X1948880D03*
X1951439Y526250D03*
X1948880D03*
X1953998D03*
Y519250D03*
X1931059Y546500D03*
X1928500D03*
X1931059Y553500D03*
X1925941D03*
X1928500D03*
X1925941Y546500D03*
X1931059Y599000D03*
X1928500Y606000D03*
X1925941D03*
Y599000D03*
X1931059Y606000D03*
X1967040Y506010D03*
X1961922Y513010D03*
X1964481Y506010D03*
X1967040Y513010D03*
X1961922Y506010D03*
X1969500Y583300D03*
X1966941D03*
X1964382D03*
X1964882Y570000D03*
X1970000Y563000D03*
X1967441D03*
X1970000Y570000D03*
X1964882Y563000D03*
X1964382Y590300D03*
X1969500D03*
G54D27*
X23940Y24559D03*
X20320Y53240D03*
X10440Y564000D03*
X12130Y529080D03*
X134164Y209283D03*
X134374Y241333D03*
X133850Y273300D03*
X134174Y305323D03*
Y337533D03*
X134434Y369363D03*
X783752Y209163D03*
X783782Y241283D03*
Y273533D03*
X784492Y305563D03*
X784322Y337353D03*
X783712Y369433D03*
G54D138*
X1465100Y521800D03*
Y516100D03*
X1465000Y537850D03*
Y532150D03*
X1498000Y525200D03*
Y519500D03*
X1487700Y537900D03*
Y532200D03*
X1611300Y491500D03*
Y497200D03*
X1606800Y474700D03*
Y480400D03*
G54D174*
X1712012Y195587D03*
G54D45*
X42724Y644684D03*
Y644656D03*
Y654684D03*
Y654656D03*
X67724Y644684D03*
Y644656D03*
Y654684D03*
Y654656D03*
X221656Y644656D03*
X196656D03*
X231446Y644756D03*
Y644784D03*
X221656Y644684D03*
X196656D03*
X221656Y654656D03*
X196656D03*
X231446Y654756D03*
Y654784D03*
X221656Y654684D03*
X196656D03*
X256446Y644756D03*
Y644784D03*
Y654756D03*
Y654784D03*
X409240Y644564D03*
X384240D03*
X418914Y644486D03*
Y644514D03*
X409240Y644536D03*
X384240D03*
X409240Y654564D03*
X384240D03*
X418914Y654486D03*
Y654514D03*
X409240Y654536D03*
X384240D03*
X443914Y644486D03*
Y644514D03*
Y654486D03*
Y654514D03*
X596707Y644293D03*
X571707D03*
X596708Y644266D03*
X571708D03*
X596707Y654293D03*
X571707D03*
X596708Y654266D03*
X571708D03*
X606462Y644245D03*
X631462D03*
X606462Y644217D03*
X631462D03*
X606462Y654245D03*
X631462D03*
X606462Y654217D03*
X631462D03*
X912351Y644245D03*
X887351D03*
X912351Y644273D03*
X887351D03*
X912351Y654245D03*
X887351D03*
X912351Y654273D03*
X887351D03*
X922116Y644206D03*
X947116D03*
X922116Y644234D03*
X947116D03*
X922116Y654206D03*
X947116D03*
X922116Y654234D03*
X947116D03*
X1200877Y644262D03*
Y644234D03*
Y654262D03*
Y654234D03*
X1225877Y644262D03*
X1235614Y644236D03*
X1260614D03*
X1235614Y644264D03*
X1260614D03*
X1225877Y644234D03*
Y654262D03*
X1235614Y654236D03*
X1260614D03*
X1235614Y654264D03*
X1260614D03*
X1225877Y654234D03*
X1514375Y644292D03*
Y644264D03*
Y654292D03*
Y654264D03*
X1539375Y644292D03*
Y644264D03*
Y654292D03*
Y654264D03*
G54D72*
X53953Y649635D03*
X242675Y649735D03*
X430143Y649465D03*
X617691Y649196D03*
X933345Y649185D03*
X1246843Y649215D03*
G54D183*
X1724807Y451179D03*
X1841929Y235430D03*
X1851250Y584622D03*
Y576748D03*
Y568874D03*
G54D18*
X-17392Y478512D03*
X2621Y32939D03*
X2008Y79298D03*
X3474Y48572D03*
X11300Y53240D03*
X41508Y402597D03*
X45450Y348600D03*
X-1458Y462804D03*
X-5602Y498621D03*
X-10669Y516148D03*
X12217Y480254D03*
X-12210Y521200D03*
X37618Y502853D03*
X28246Y491557D03*
X418Y534500D03*
X2700Y564500D03*
X-9500Y539400D03*
X-9200Y574400D03*
X79670Y135828D03*
X60723Y156869D03*
X95777Y129396D03*
X76899Y157895D03*
X76300Y166500D03*
X57700Y169300D03*
X78100Y189400D03*
X68200Y191200D03*
X62400Y166500D03*
X67700Y255100D03*
X70400Y270200D03*
X90300Y224400D03*
X69300Y306000D03*
X76600Y342000D03*
X51498Y295470D03*
X62807Y305396D03*
X107300Y327600D03*
X85500Y341000D03*
X70900Y317400D03*
X80513Y338412D03*
X94850Y320650D03*
X95000Y315300D03*
X56100Y361900D03*
X56600Y356400D03*
X67130Y369550D03*
X55881Y527427D03*
X58597Y498898D03*
X55528Y478782D03*
X68700Y532400D03*
X57684Y647686D03*
Y651626D03*
X115300Y-5600D03*
X118600Y159500D03*
X124980Y241380D03*
X125460Y273080D03*
X110740Y240361D03*
X124400Y305080D03*
X110470Y308170D03*
X121620Y339500D03*
X119018Y369791D03*
X164830Y422339D03*
X157776Y410444D03*
X115750Y412130D03*
X226039Y400962D03*
X206696Y647714D03*
Y651654D03*
X267859Y209109D03*
X271239Y203260D03*
X277999Y218860D03*
X281379Y209109D03*
X288139Y201309D03*
Y209109D03*
X277999Y199360D03*
X274619Y201309D03*
Y209109D03*
Y205210D03*
X264092Y242260D03*
X271239D03*
X267859Y248109D03*
X264179Y261760D03*
X271239D03*
Y253960D03*
X288139Y228610D03*
X277999Y226660D03*
X288139Y220809D03*
X281379Y236409D03*
X284759Y250060D03*
X288139Y240309D03*
X281379Y244209D03*
X277999Y257860D03*
X288139Y267609D03*
Y259809D03*
X277999Y265660D03*
X274619Y271509D03*
X291519Y273460D03*
X277999D03*
X288139Y322209D03*
X281379D03*
X284759Y335860D03*
X277999D03*
X288139Y330009D03*
X281379Y341709D03*
Y330009D03*
X271239Y339760D03*
X252170Y337860D03*
X271239Y394359D03*
X267859Y392410D03*
X271239Y398260D03*
X284759Y355360D03*
X274619Y400209D03*
X281379D03*
X277999Y398260D03*
X274619Y396309D03*
X288139Y388509D03*
X291519Y394359D03*
X281379Y388509D03*
X284759Y394359D03*
X277999Y355360D03*
X284759Y347560D03*
X281379Y361209D03*
X284759Y374860D03*
X271239Y347560D03*
X264179D03*
X277999Y374860D03*
X288139Y369010D03*
X281379Y380709D03*
Y369010D03*
X260000Y371000D03*
X260900Y353123D03*
X267400Y364400D03*
X243705Y354394D03*
X243259Y363354D03*
X262200Y361200D03*
X256300Y349800D03*
Y358800D03*
X246406Y647786D03*
Y651726D03*
X308418Y216909D03*
X294899D03*
X301659D03*
X294899Y205210D03*
Y197409D03*
X352357Y218860D03*
X345598D03*
X338838Y214960D03*
X342218Y216909D03*
X338838Y207158D03*
Y203258D03*
X345598Y211060D03*
X348978Y213009D03*
X342218Y205210D03*
X298279Y222760D03*
X305039D03*
X328698Y236409D03*
Y244209D03*
X321938Y240309D03*
X294899Y232509D03*
X301659Y244209D03*
Y232509D03*
X318558Y222760D03*
X311798Y234460D03*
X305039Y238360D03*
X294899Y240309D03*
X311798Y226660D03*
X318558Y230559D03*
X332078Y222760D03*
X328698Y224709D03*
Y228610D03*
X332078Y230560D03*
X311798Y242260D03*
X315178Y248109D03*
X308418D03*
X305039Y257860D03*
X328698Y255909D03*
X325318Y261760D03*
X294899Y252009D03*
X301659Y263709D03*
Y252009D03*
X294899Y259809D03*
X332078Y261760D03*
X315178Y271509D03*
X311798Y265660D03*
X321938Y271509D03*
X308418D03*
X318558Y265660D03*
X294899Y271509D03*
Y267609D03*
X332078Y273460D03*
X298279D03*
X328698Y275409D03*
X332078Y277360D03*
X325318D03*
X328698Y279310D03*
X321938D03*
X301659Y271509D03*
X328698D03*
X298279Y269560D03*
X342218Y224709D03*
X345598Y230559D03*
X348978Y224709D03*
X355737D03*
X352357Y230559D03*
X335458Y220809D03*
X345598Y222760D03*
X335458Y228610D03*
X338838Y230560D03*
Y273460D03*
Y269560D03*
X335458Y275409D03*
X338838Y277360D03*
X335458Y279310D03*
Y271509D03*
X348978Y236409D03*
X355737D03*
X342218D03*
X319816Y257829D03*
X298279Y320260D03*
X294899Y330009D03*
X352357Y339760D03*
X355737Y341709D03*
X298279Y335860D03*
X321938Y326110D03*
X311798Y331960D03*
X325318D03*
X315178Y326110D03*
X318558Y331960D03*
X335458Y341709D03*
X301659D03*
X294899D03*
X305039Y335860D03*
X338838D03*
X328698Y341709D03*
X342218D03*
X332078Y335860D03*
Y370959D03*
X328698Y369010D03*
X294899Y400209D03*
X315178Y384609D03*
Y380709D03*
X332078Y374860D03*
X328698Y372909D03*
X355737Y345609D03*
X335458Y369010D03*
X338838Y363160D03*
X352357Y343660D03*
X348978Y384609D03*
X335458Y376809D03*
X345598Y374860D03*
X301659Y361209D03*
X332078Y351460D03*
X321938Y357309D03*
X335458D03*
X325318Y351460D03*
X301659Y380709D03*
X328698Y361209D03*
X305039Y374860D03*
X294899Y380709D03*
X308418D03*
X298279Y374860D03*
X345598Y386560D03*
X341892Y396301D03*
X311798Y363160D03*
X318558Y374860D03*
Y363160D03*
X294899Y361209D03*
X305039Y355360D03*
X298279Y367060D03*
X342218Y369010D03*
Y357309D03*
X345598Y363160D03*
Y351460D03*
X348978Y357309D03*
Y369010D03*
X355737Y380709D03*
X352357Y374860D03*
X294899Y388509D03*
X338838Y374860D03*
X348978Y380709D03*
X351192Y402800D03*
X342218Y380709D03*
X355737Y357309D03*
Y369010D03*
X352357Y363160D03*
Y351460D03*
X315178Y369010D03*
X298279Y355360D03*
Y347560D03*
X321938Y369010D03*
X318495Y348600D03*
X371700Y112300D03*
X365877Y218860D03*
X372637D03*
X386157Y211060D03*
X379397Y207159D03*
Y218860D03*
X359117Y211060D03*
Y218860D03*
X386157D03*
X357987Y193507D03*
X378267D03*
X372637Y211060D03*
X399676D03*
X392916D03*
X399676Y218860D03*
X407706Y216909D03*
X392916Y218860D03*
X376017Y224709D03*
X369257D03*
X362497D03*
X389537D03*
X382777D03*
X396296D03*
X407706Y236409D03*
Y244209D03*
X415634Y243496D03*
Y231797D03*
X396296Y236409D03*
X359117Y230559D03*
X379397Y234460D03*
X386157Y230559D03*
X407706Y224709D03*
X392916Y230559D03*
X399676D03*
X389537Y236409D03*
X362497D03*
X369257D03*
X365877Y230559D03*
X372637D03*
X389537Y357309D03*
X365877Y351460D03*
X372637D03*
X362497Y345609D03*
X359117Y343660D03*
X403056Y396309D03*
X411086Y394359D03*
X399676Y386560D03*
X411086D03*
Y382660D03*
Y378760D03*
X398546Y402900D03*
X402892Y400400D03*
X403056Y369010D03*
X399676Y363160D03*
X382777Y369010D03*
X365877Y363160D03*
X372637D03*
X362497Y369010D03*
X369257D03*
X389537Y380709D03*
X392916Y374860D03*
X359117D03*
Y386560D03*
X379397Y374860D03*
X382777Y380709D03*
X369257D03*
X379397Y386560D03*
X399676Y374860D03*
X403056Y380709D03*
X386157Y386560D03*
X396296Y369010D03*
X386157Y374860D03*
X376017Y380709D03*
X365877Y374860D03*
X372637D03*
X362497Y380709D03*
X396296D03*
X392916Y386560D03*
X372637D03*
X376017Y369010D03*
X389537D03*
X392916Y363160D03*
X386157D03*
X359117Y351460D03*
Y363160D03*
X362497Y357309D03*
X379397Y363160D03*
X369257Y357309D03*
X415500Y391900D03*
X371070Y498650D03*
X394280Y647594D03*
Y651534D03*
X419214Y218147D03*
X436113Y235696D03*
Y220096D03*
Y227896D03*
X446253Y222047D03*
Y225947D03*
X432733Y222047D03*
Y225947D03*
X442873Y220096D03*
Y227896D03*
X453013Y225947D03*
X439493Y229847D03*
Y222047D03*
Y225947D03*
X425974Y222047D03*
X419214Y225947D03*
X442873Y235696D03*
X429354Y231797D03*
X449633D03*
Y239596D03*
X452865Y270081D03*
X439764Y263699D03*
X449288Y266435D03*
X444752Y264188D03*
X453013Y253247D03*
X463153Y220096D03*
Y227896D03*
X473292Y222047D03*
Y225947D03*
X459773Y229847D03*
Y222047D03*
X466533Y241547D03*
X463153Y235696D03*
X473292Y241547D03*
X469913Y235696D03*
X456393D03*
Y247396D03*
X463153D03*
X476672D03*
X456393Y220096D03*
X466533Y225947D03*
Y253247D03*
X473292D03*
X459773D03*
X476672Y262996D03*
X469913Y266896D03*
X466300Y277700D03*
X461400Y274600D03*
X447800Y335900D03*
X466066Y292452D03*
X466734Y287074D03*
X466100Y300021D03*
X471033Y339047D03*
X472692Y292385D03*
X462200Y332100D03*
X474057Y299057D03*
X430474Y358547D03*
X433854Y356596D03*
X467653Y379996D03*
X443993Y354647D03*
X460893Y368296D03*
X450753Y374146D03*
X464273D03*
X454133Y368296D03*
X423714Y366347D03*
Y358547D03*
X437233Y366347D03*
X477792Y374146D03*
X427094Y387796D03*
X471033Y374146D03*
X474413Y368296D03*
X430474Y381947D03*
X423714Y378047D03*
X433854Y387796D03*
X423714Y393647D03*
X467653Y387796D03*
X447373Y383896D03*
X460893D03*
X474413D03*
X450753Y389747D03*
X440613Y383896D03*
X454133D03*
X443993Y389747D03*
X467653Y360496D03*
X447373D03*
X457513Y374146D03*
X430474Y362447D03*
Y370247D03*
X471033Y354647D03*
X460893Y360496D03*
X474413D03*
X464273Y354647D03*
X450753D03*
X440613Y360496D03*
X454133D03*
X433874Y647516D03*
Y651456D03*
X483432Y247396D03*
X508212Y243496D03*
X486812Y253247D03*
X480052D03*
X491312Y272747D03*
X494692Y266896D03*
X528491Y259096D03*
X504832Y307847D03*
X487932Y305896D03*
X491312Y303947D03*
X501452Y305896D03*
X494692Y298096D03*
X498072Y307847D03*
X484552Y303947D03*
X487932Y294196D03*
X491312Y296147D03*
X494692Y301996D03*
X487932D03*
X501452Y309797D03*
X487932Y298096D03*
X511592Y311747D03*
Y303947D03*
X481172Y321496D03*
X487932Y313696D03*
X481172Y325396D03*
X491312Y315647D03*
X481172Y317596D03*
X518352Y311747D03*
X528491Y305896D03*
X484552Y311747D03*
X481172Y286396D03*
X484552Y342947D03*
X481172Y364396D03*
Y383896D03*
X566051Y211555D03*
X562861Y205503D03*
X552151Y237647D03*
X548771Y305896D03*
X552151Y300047D03*
X548771Y301996D03*
X552151Y307847D03*
Y303947D03*
X555831Y301996D03*
X548771Y298096D03*
X542011Y317596D03*
X545391Y389747D03*
X542011Y391696D03*
Y395597D03*
Y387796D03*
X545391Y393647D03*
X581747Y647323D03*
Y651263D03*
X660600Y84800D03*
Y170000D03*
X653000Y256500D03*
X639000Y261100D03*
X650856Y292256D03*
X607339Y458540D03*
X657200Y522300D03*
X614870Y492153D03*
X641500Y487400D03*
X636600Y480900D03*
X613700Y474560D03*
X621422Y647247D03*
X658600Y590900D03*
X621422Y651187D03*
X667000Y28400D03*
X710000Y21000D03*
X690515Y27586D03*
X667900Y84100D03*
X682700Y34400D03*
X679800Y53600D03*
X710700Y48400D03*
X691830Y89820D03*
X670600Y144900D03*
Y150000D03*
X713248Y276494D03*
X709175Y221875D03*
X671733Y253567D03*
X673240Y274190D03*
X702503Y296653D03*
X700700Y304300D03*
X687427Y380000D03*
X692000Y345400D03*
X680200Y432100D03*
X682083Y520789D03*
X669150Y489450D03*
X725190Y510910D03*
X725021Y568200D03*
X688300Y532900D03*
X722500Y583800D03*
X682340Y584970D03*
X725600Y594600D03*
X729798Y84503D03*
X726815Y75315D03*
X771750Y242120D03*
X771800Y274850D03*
X774460Y336700D03*
X773580Y305230D03*
X774490Y369520D03*
X758150Y406880D03*
X728141Y579451D03*
X760300Y604300D03*
X848900Y217000D03*
X842500Y396400D03*
X802900Y417615D03*
X869877Y-5735D03*
X906470Y-5775D03*
X910900Y211803D03*
Y203260D03*
X910455Y340644D03*
X902559Y352500D03*
X906622Y348377D03*
X908300Y367500D03*
X903600Y361500D03*
X909450Y395500D03*
X903550Y398260D03*
X908650Y403450D03*
X897391Y647303D03*
Y651243D03*
X930987Y209109D03*
X937747Y201309D03*
Y209109D03*
X927607Y199360D03*
X924227Y201309D03*
Y209109D03*
Y205210D03*
X930987Y216909D03*
X934367Y203260D03*
Y211060D03*
X958026Y216909D03*
X944507D03*
X951267Y213009D03*
Y216909D03*
X944507Y197409D03*
X915457Y207159D03*
X930987Y248109D03*
X937747Y244209D03*
X927607Y246160D03*
X934367Y242260D03*
X930987Y228610D03*
X937747D03*
X927607Y222760D03*
X913700Y242260D03*
X920847D03*
Y250060D03*
X927607Y226660D03*
X917467Y248109D03*
X934367Y222760D03*
X927607Y238360D03*
X934367Y250060D03*
Y238360D03*
X917467Y271509D03*
X927607Y273460D03*
X924227Y271509D03*
X913787Y257860D03*
X920847Y261760D03*
Y253960D03*
X930987Y255909D03*
X934367Y269560D03*
X937747Y267609D03*
X927607Y261760D03*
X937747Y259809D03*
X934367Y261760D03*
X930987Y263709D03*
X947887Y222760D03*
X954647D03*
X951267Y220809D03*
X971546Y240309D03*
Y244209D03*
X961406Y242260D03*
X964786Y244209D03*
X961406Y246160D03*
X964786Y248109D03*
X958026D03*
X968166Y250060D03*
X971546Y279310D03*
X944507Y271509D03*
X964786Y263709D03*
Y275409D03*
X961406Y265660D03*
X971546Y271509D03*
X958026D03*
X968166Y265660D03*
Y273460D03*
X944507Y267609D03*
X947887Y269560D03*
X951267Y271509D03*
X947887Y273460D03*
X941127D03*
X944507Y232509D03*
X971546Y228610D03*
X968166Y222760D03*
X951267Y232509D03*
Y252009D03*
Y244209D03*
X947887Y257860D03*
X968166Y230559D03*
X964786Y228610D03*
X944507Y259809D03*
X954647Y234460D03*
X961406Y226660D03*
X944507Y240309D03*
X954647Y253960D03*
Y238360D03*
Y261760D03*
X951267Y263709D03*
X947887Y250060D03*
X944507Y252009D03*
X964786Y236409D03*
X961406Y234460D03*
X954647Y257860D03*
X968166Y234460D03*
X968218Y254594D03*
X967589Y260093D03*
X913787Y335860D03*
X920847Y331960D03*
Y339760D03*
X930987Y330009D03*
Y341709D03*
X937747Y330009D03*
X927607Y335860D03*
X934367D03*
Y320260D03*
X927607Y324160D03*
X947887Y335860D03*
X954647D03*
X944507Y341709D03*
X951267D03*
X968166Y331960D03*
X964786Y326110D03*
X947887Y320260D03*
X941127D03*
X944507Y330009D03*
X961406Y331960D03*
X971546Y326110D03*
X967830Y340840D03*
X934367Y367060D03*
X913787Y351460D03*
X920847D03*
X927607Y370959D03*
X917467Y345609D03*
X934367Y347560D03*
X927607Y359260D03*
X934367Y355360D03*
X927607Y351460D03*
X937747Y372909D03*
X927607Y378760D03*
X934367D03*
Y386560D03*
X930987Y392410D03*
X937747Y396309D03*
X930987Y400209D03*
X917467Y392410D03*
X924227Y396309D03*
X971546Y357309D03*
X951267Y365109D03*
Y353409D03*
X944507Y365109D03*
X961406Y367060D03*
X964786Y361209D03*
X947887Y347560D03*
X954647Y359260D03*
X971546Y345609D03*
X944507Y357309D03*
X971546Y365109D03*
X958026Y349509D03*
X947887Y382660D03*
X958026Y376809D03*
X944507D03*
X954647Y382660D03*
X951267Y372909D03*
X944507Y392410D03*
X941127Y386560D03*
X971546Y372909D03*
X964786D03*
X944507Y400209D03*
X964786Y384609D03*
Y380709D03*
X967498Y348611D03*
X916700Y403300D03*
X937076Y647236D03*
Y651176D03*
X991826Y213009D03*
X988446Y214960D03*
X991826Y216909D03*
X988446Y207158D03*
Y203258D03*
X995206Y211060D03*
X998586Y213009D03*
X1025625Y216909D03*
X1015485Y218860D03*
X1022245D03*
X1032385Y213009D03*
X1029005Y207159D03*
X1012105Y213009D03*
X1008725Y218860D03*
X1005345Y216909D03*
X1025625Y213009D03*
X991826Y209109D03*
X995206Y207159D03*
X1022245D03*
X1005345Y213009D03*
X1029005Y218860D03*
X1001965D03*
X1018865Y213009D03*
X978306Y236409D03*
Y240309D03*
Y244209D03*
X974926Y246160D03*
X985066Y240309D03*
X981686Y246160D03*
X991826Y224709D03*
X988446Y222760D03*
X998586Y228610D03*
X985066Y220809D03*
X981686Y222760D03*
X978306Y224709D03*
X981686Y226660D03*
X985066Y228610D03*
X978306D03*
X981686Y230559D03*
X985066Y232509D03*
X995206Y250060D03*
X998586Y252009D03*
X995206Y253960D03*
X998586Y255909D03*
X995206Y257860D03*
X998586Y259809D03*
X995206Y261760D03*
X988446Y269560D03*
X985066Y271509D03*
X978306D03*
X988446Y273460D03*
X981686D03*
X985066Y275409D03*
X978306D03*
X988446Y277360D03*
X981686D03*
X974926D03*
X985066Y279310D03*
X978306D03*
X1025625Y224709D03*
X1022245Y222760D03*
X1018865Y224709D03*
X1012105D03*
X1032385D03*
X1029005Y222760D03*
X1005345Y224709D03*
X1001965Y230559D03*
X1012105Y248109D03*
X1008725Y250060D03*
X1001965D03*
X1032385Y240309D03*
X1029005Y242260D03*
X1032385Y244209D03*
X1025625D03*
X1029005Y246160D03*
X1022245D03*
X1015485D03*
X1018865Y248109D03*
X1015485Y250060D03*
X1005345Y252009D03*
X1008725Y253960D03*
X1001965D03*
X1005345Y255909D03*
X1001965Y257860D03*
X1012105Y252009D03*
X985066Y263709D03*
X988446Y257860D03*
X1022245Y242260D03*
X1018865Y228610D03*
X1012105Y236409D03*
X1018865D03*
X1015485Y230559D03*
X1022245D03*
X991826Y236409D03*
Y228610D03*
X995206Y242260D03*
X1015485D03*
X1029005Y230559D03*
X998586Y236409D03*
Y224709D03*
X1008725Y246160D03*
X1001965Y242260D03*
X1005345Y236409D03*
X1008725Y230559D03*
Y242260D03*
X1001965Y246160D03*
X1025625Y236409D03*
X981686Y257860D03*
Y265660D03*
Y253960D03*
X974926Y261760D03*
Y257860D03*
X978306Y263709D03*
X1032385Y236409D03*
X998586Y337809D03*
X991826D03*
X978306D03*
X985066Y333909D03*
X974926Y331960D03*
X1001965Y339760D03*
X1005345Y341709D03*
X978306Y361209D03*
X974926Y351460D03*
X981686D03*
X995206Y367060D03*
X988446Y370959D03*
X981686Y343660D03*
X991826Y349509D03*
X995206Y347560D03*
X981686Y370959D03*
X978306Y369010D03*
X985066D03*
Y365109D03*
X988446Y363160D03*
X995206Y378760D03*
X998586Y372909D03*
X988446Y378760D03*
X998586Y384609D03*
X985066Y376809D03*
X981686Y374860D03*
X995206D03*
X991826Y384609D03*
X991500Y396301D03*
X1032385Y357309D03*
X1022245Y351460D03*
X1029005D03*
X1001965Y347560D03*
X1012105Y345609D03*
X1015485Y347560D03*
X1008725D03*
X1001965Y367060D03*
X1015485Y355360D03*
X1008725Y367060D03*
X1022245Y390460D03*
X1000800Y402800D03*
X1025625Y372909D03*
X1018865Y384609D03*
Y372909D03*
X1012105D03*
X1022245Y378760D03*
X1032385Y384609D03*
X1001965Y378760D03*
X1032385Y372909D03*
X1029005Y378760D03*
X1012105Y384609D03*
X1008725Y378760D03*
X1005345Y372909D03*
Y384609D03*
X1025625D03*
X988446Y343660D03*
X1015485Y378760D03*
Y367060D03*
X1022245D03*
X1012105Y361209D03*
X1018865D03*
X991826D03*
X998586D03*
X1029005Y367060D03*
X995206Y355360D03*
X1001965D03*
X1005345Y361209D03*
X1008725Y355360D03*
X1025625Y361209D03*
X1032385D03*
X985066Y357309D03*
X1001946Y621460D03*
X1049284Y218860D03*
X1057314Y216909D03*
X1035765Y218860D03*
X1049284Y211060D03*
X1089101Y218147D03*
X1065242Y216196D03*
X1039145Y213009D03*
X1042524Y211060D03*
X1049284Y207159D03*
X1045904Y216909D03*
X1042524Y218860D03*
X1045904Y244209D03*
Y240309D03*
X1035765Y222760D03*
X1039145Y224709D03*
X1042524Y222760D03*
X1045904Y224709D03*
X1049284Y242260D03*
X1039145Y240309D03*
X1042524Y242260D03*
X1035765D03*
X1039145Y244209D03*
X1042524Y246160D03*
X1035765D03*
X1092481Y220096D03*
Y227896D03*
X1089101Y229847D03*
X1075582Y222047D03*
X1065242Y227896D03*
Y231797D03*
X1072202Y220096D03*
Y227896D03*
X1068822Y225947D03*
Y222047D03*
X1095861Y241547D03*
X1092481Y235696D03*
Y239596D03*
X1072202Y247396D03*
X1065242Y243496D03*
X1085721Y220096D03*
X1095861Y225947D03*
X1082341D03*
X1095700Y265900D03*
X1078962Y231797D03*
X1082341Y241547D03*
X1085721Y235696D03*
X1075582Y241547D03*
X1045904Y236409D03*
X1035765Y230559D03*
X1072202Y235696D03*
X1057314Y228610D03*
X1042524Y230559D03*
X1049284D03*
X1057314Y236409D03*
X1049284Y355360D03*
X1052664Y361209D03*
X1035765Y367060D03*
X1045904Y384609D03*
X1039145D03*
X1049284Y390460D03*
X1052664Y396309D03*
X1049284Y386560D03*
X1048154Y402900D03*
X1052500Y400400D03*
X1049284Y378760D03*
X1039145Y372909D03*
X1042524Y378760D03*
X1035765D03*
X1045904Y372909D03*
X1083462Y356596D03*
X1086841Y370247D03*
X1073322Y358547D03*
X1083462Y364396D03*
X1093601Y354647D03*
X1090221Y360496D03*
X1080082Y358547D03*
X1093601Y381947D03*
X1090221Y387796D03*
X1073322Y393647D03*
X1083462Y383896D03*
X1073322Y378047D03*
X1080082Y389747D03*
X1060694Y394359D03*
Y386560D03*
Y382660D03*
Y378760D03*
X1086841Y378047D03*
X1090221Y376096D03*
X1093601Y374146D03*
X1061055Y363160D03*
X1060963Y370959D03*
X1064371Y367060D03*
X1076702Y364396D03*
X1073322Y370247D03*
X1080082Y374146D03*
X1045904Y361209D03*
X1052664Y372909D03*
X1042524Y367060D03*
X1049284D03*
X1039145Y361209D03*
X1076702Y383896D03*
X1066300Y396700D03*
X1109381Y218147D03*
X1116141Y206446D03*
X1133040Y216196D03*
X1129660Y218147D03*
X1133040Y212296D03*
X1106001Y220096D03*
X1116141Y225947D03*
X1102621Y222047D03*
Y225947D03*
X1112761Y220096D03*
Y227896D03*
X1109381Y229847D03*
X1116141Y241547D03*
X1112761Y235696D03*
X1119521Y243496D03*
Y235696D03*
X1106001D03*
X1102621Y241547D03*
X1099241Y231797D03*
Y243496D03*
Y235696D03*
X1107600Y271900D03*
X1114340Y280560D03*
X1151060Y251296D03*
X1126280Y220096D03*
X1133040Y231797D03*
X1122900Y222047D03*
Y225947D03*
X1133040Y220096D03*
X1129660Y229847D03*
X1126280Y235696D03*
X1122900Y241547D03*
X1157820Y243496D03*
X1133040Y239596D03*
X1136420Y261047D03*
X1133040Y262996D03*
X1151060Y255196D03*
X1147680Y261047D03*
X1144300Y259096D03*
X1151060Y262996D03*
X1147680Y253247D03*
Y257147D03*
X1134160Y272747D03*
X1109381Y264947D03*
X1129660Y249347D03*
X1109381D03*
X1126280Y247396D03*
X1102621Y249347D03*
X1116141D03*
X1129660Y257147D03*
X1122900Y253247D03*
X1133040Y247396D03*
Y255196D03*
X1136420Y253247D03*
X1121500Y273338D03*
X1113740Y274852D03*
X1116096Y295809D03*
X1099391Y337001D03*
X1105800Y336830D03*
X1114839Y320075D03*
X1157820Y309797D03*
X1134160Y303947D03*
X1130780Y321496D03*
X1137540Y313696D03*
X1130780Y325396D03*
X1140920Y315647D03*
X1134160Y319547D03*
X1130780Y317596D03*
Y333196D03*
X1134160Y331247D03*
X1115230Y289252D03*
X1101100Y332200D03*
X1111900Y334199D03*
X1123769Y290624D03*
X1123256Y282984D03*
X1123747Y298283D03*
X1113881Y370247D03*
X1100361D03*
X1103741Y360496D03*
X1100361Y354647D03*
Y362447D03*
X1113881Y354647D03*
X1110501Y356596D03*
Y360496D03*
X1096981Y356596D03*
X1117261D03*
X1096981Y364396D03*
X1117261D03*
X1107121Y366347D03*
X1103741Y387796D03*
X1100361Y381947D03*
X1113881Y389747D03*
X1110501Y383896D03*
X1117261Y379996D03*
X1096981Y391696D03*
X1117261Y383896D03*
Y387796D03*
X1103741Y376096D03*
X1110501D03*
X1124021Y368296D03*
X1130780Y364396D03*
X1124021Y360496D03*
X1120641Y354647D03*
Y362447D03*
X1140920Y354647D03*
X1137540Y356596D03*
X1124021Y383896D03*
X1120641Y389747D03*
X1144300Y399496D03*
X1130780Y383896D03*
Y387796D03*
X1140920Y393647D03*
X1137540Y379996D03*
Y383896D03*
Y387796D03*
X1134160Y374146D03*
X1120641D03*
X1127400D03*
X1157820Y383896D03*
X1156699Y401447D03*
X1127400Y370247D03*
X1147680D03*
X1157820Y364396D03*
X1216100Y106520D03*
X1208519Y218147D03*
X1178099Y223996D03*
X1174719Y241547D03*
X1178099Y239596D03*
X1174719Y245447D03*
X1178099Y251296D03*
X1171339Y270796D03*
X1178099Y266896D03*
Y262996D03*
X1191619Y223996D03*
X1181479Y253247D03*
X1164580Y243496D03*
X1181479Y331247D03*
X1198379Y321496D03*
X1194999Y323446D03*
X1181479Y315647D03*
X1191619Y337096D03*
X1181479Y323446D03*
X1171339Y337096D03*
X1174719Y331247D03*
X1178099Y321496D03*
X1174719Y327347D03*
X1167960Y335147D03*
X1171339Y329296D03*
X1178099Y333196D03*
Y325396D03*
X1171339Y333196D03*
X1178099Y329296D03*
X1174719Y319547D03*
X1161201Y401447D03*
X1178099Y368296D03*
X1164580Y391696D03*
X1171339Y352696D03*
X1164580Y364396D03*
X1167960Y350747D03*
X1161200Y362447D03*
Y358547D03*
X1201000Y402200D03*
X1210917Y647292D03*
Y651232D03*
X1257500Y142000D03*
X1259371Y129171D03*
X1268401Y137250D03*
X1262900Y140050D03*
X1221300Y106600D03*
X1235165Y129710D03*
X1229600Y128300D03*
X1242000Y125000D03*
X1263300Y172440D03*
X1263401Y240889D03*
X1276337Y243490D03*
X1269500Y235900D03*
X1240640Y495440D03*
X1246300Y495000D03*
X1249500Y483800D03*
X1242100Y484100D03*
X1254000Y477310D03*
X1266900Y469500D03*
X1250574Y647266D03*
Y651206D03*
X1327700Y31200D03*
X1297010Y21510D03*
X1325100Y145000D03*
X1315180Y169950D03*
X1315130Y164870D03*
X1298051Y204392D03*
X1336100Y200300D03*
X1285000Y211000D03*
X1287743Y262956D03*
X1308130Y252600D03*
X1334600Y228400D03*
X1294909Y248409D03*
X1308400Y263300D03*
X1302000Y282300D03*
X1330257Y293443D03*
X1315183Y289917D03*
X1315177Y297177D03*
X1335250Y341350D03*
X1327400Y327195D03*
X1317834Y342234D03*
X1336600Y323400D03*
X1333500Y356500D03*
X1315496Y354100D03*
X1321068Y349234D03*
X1332075Y438600D03*
X1314700Y577400D03*
X1302200Y605300D03*
X1375212Y967D03*
X1371123Y41033D03*
X1369500Y107500D03*
X1380100Y165000D03*
Y160000D03*
X1393500Y213250D03*
X1402918Y278082D03*
X1390800Y279000D03*
X1361558Y325942D03*
X1352285Y321824D03*
X1349700Y341500D03*
X1378900Y336600D03*
X1377966Y332783D03*
X1378900Y341000D03*
X1350200Y332700D03*
X1392657Y288900D03*
X1386400Y362150D03*
X1349700Y347800D03*
X1383806Y372597D03*
X1399960Y391476D03*
X1386792Y378855D03*
X1378071Y386200D03*
X1344253Y354242D03*
X1373830Y398940D03*
X1378880Y352370D03*
X1390100Y432500D03*
X1377028Y458125D03*
X1375100Y447500D03*
X1390100Y452500D03*
X1372028Y458125D03*
X1352266Y503491D03*
X1373426Y516634D03*
X1377700Y587500D03*
X1388600Y577800D03*
X1390389Y585211D03*
X1378930Y612980D03*
X1452017Y16800D03*
X1457674Y16774D03*
X1415400Y23730D03*
X1421400Y16700D03*
X1456790Y87112D03*
X1420337Y48377D03*
X1414091Y46412D03*
X1464800Y132900D03*
X1435500Y145400D03*
X1439451Y140149D03*
X1441600Y146400D03*
X1434581Y117098D03*
X1428000Y124600D03*
X1444500Y126600D03*
X1433500Y151419D03*
X1457572Y134510D03*
X1457694Y96494D03*
X1415712Y213300D03*
X1417963Y206280D03*
X1465610Y214440D03*
X1411950Y198838D03*
X1457043Y161495D03*
X1432600Y161300D03*
X1406050Y200850D03*
X1465650Y209350D03*
X1450250Y161330D03*
X1454079Y157468D03*
X1466400Y195243D03*
X1415800Y188600D03*
X1415819Y181981D03*
X1427100Y159100D03*
X1415985Y174791D03*
X1443715Y253769D03*
X1449919Y252409D03*
X1451858Y257896D03*
X1423475Y269600D03*
X1464340Y247410D03*
X1437923Y269627D03*
X1407200Y269600D03*
X1441600Y258300D03*
X1425304Y234733D03*
X1425469Y239829D03*
X1449497Y264519D03*
X1447345Y260523D03*
X1462950Y267913D03*
X1444948Y264505D03*
X1465830Y271083D03*
X1439700Y300400D03*
X1423407Y281739D03*
X1436812Y285989D03*
X1432344Y289437D03*
X1410990Y334390D03*
X1438958Y329999D03*
X1443150Y315080D03*
X1464476Y315500D03*
X1443400Y285700D03*
X1422553Y326188D03*
X1431194Y327707D03*
X1434624Y294777D03*
X1460154Y382938D03*
X1454814Y379245D03*
X1429100Y361300D03*
X1425828Y347928D03*
X1451850Y392790D03*
X1458800Y426700D03*
X1453400Y423000D03*
X1407200Y521500D03*
X1424116Y518484D03*
X1428200Y563500D03*
X1465950Y612290D03*
X1473550Y14150D03*
X1492700Y12300D03*
X1468000Y17100D03*
X1515000Y-3242D03*
X1525000Y-1587D03*
X1510500Y-300D03*
X1473886Y35185D03*
X1511900Y34100D03*
X1516017Y38841D03*
X1521741Y65151D03*
X1482500Y77500D03*
Y83500D03*
X1520887Y44028D03*
X1479138Y130320D03*
X1468635Y119025D03*
X1489000Y135955D03*
X1489252Y152111D03*
X1508700Y112400D03*
X1481100Y102500D03*
X1481300Y96900D03*
X1472887Y204496D03*
X1481500Y161617D03*
X1484800Y157800D03*
X1516000Y189200D03*
X1523400Y212400D03*
X1475564Y200130D03*
X1513779Y182078D03*
X1523000Y199100D03*
X1498387Y264666D03*
X1522210Y234190D03*
X1516450Y227011D03*
X1511440Y250974D03*
X1519400Y268480D03*
X1505500Y269500D03*
X1469330Y249069D03*
X1522717Y221027D03*
X1517608Y221216D03*
X1472824Y267123D03*
X1506137Y248182D03*
X1467469Y277500D03*
X1487078Y253972D03*
X1490963Y276277D03*
X1499900Y277100D03*
X1511710Y311070D03*
X1521350Y322417D03*
X1504217Y294890D03*
X1467542Y300987D03*
X1477393Y316431D03*
X1482996Y292960D03*
X1467700Y311397D03*
X1489600Y293300D03*
X1482200Y318600D03*
X1507500Y300606D03*
X1467613Y306048D03*
X1469801Y318200D03*
X1517700Y303082D03*
X1489200Y299100D03*
X1485850Y350500D03*
X1501360Y367320D03*
X1499350Y370850D03*
X1495300Y374100D03*
X1476100Y390000D03*
X1485850Y344600D03*
X1476150Y383860D03*
X1491000Y367687D03*
X1493600Y354020D03*
X1518245Y361300D03*
X1521050Y371700D03*
X1523700Y366200D03*
X1515183Y372400D03*
X1477800Y370800D03*
X1512000Y346100D03*
X1483497Y375917D03*
X1527478Y352860D03*
X1474626Y362517D03*
X1509800Y372300D03*
X1504600Y372200D03*
X1507800Y366600D03*
X1481081Y356230D03*
X1468190Y383870D03*
X1484756Y440623D03*
X1515070Y527170D03*
X1520747Y508200D03*
X1524583Y489586D03*
X1471220Y519260D03*
X1520300Y494000D03*
X1472000Y532000D03*
X1524415Y647322D03*
X1516158Y616032D03*
X1481778Y614716D03*
X1524415Y651262D03*
X1547716Y6046D03*
X1530367Y-1587D03*
X1583001Y-10700D03*
X1569553Y32168D03*
X1580398Y2300D03*
X1583256Y29400D03*
X1581409Y48148D03*
X1558285Y54807D03*
X1539299Y73184D03*
X1564100Y59266D03*
X1555623Y41553D03*
X1565637Y52524D03*
X1543200Y42303D03*
X1568950Y99252D03*
X1567820Y115200D03*
X1588600Y150500D03*
X1536000Y135000D03*
X1574665Y106417D03*
X1528346Y147595D03*
X1535061Y109559D03*
X1561693Y136074D03*
X1563506Y142982D03*
X1545500Y138500D03*
X1535338Y141386D03*
X1576870Y127078D03*
X1537249Y118153D03*
X1589700Y169000D03*
X1555800Y167300D03*
X1576679Y171209D03*
X1575600Y166000D03*
X1588847Y175137D03*
X1561000Y168500D03*
X1582627Y198617D03*
X1574600Y185400D03*
X1574500Y206100D03*
X1574700Y201100D03*
X1574900Y196000D03*
X1579700Y206200D03*
X1588799Y162838D03*
X1567500Y158100D03*
X1549000Y160500D03*
X1561400Y263000D03*
X1553532Y231913D03*
X1548996Y265700D03*
X1566260Y256040D03*
X1559350Y255050D03*
X1538443Y265371D03*
X1587500Y236486D03*
X1543400Y277900D03*
X1579600Y235100D03*
X1532526Y227200D03*
X1579900Y223500D03*
X1537150Y229238D03*
X1562900Y243600D03*
X1568230Y287330D03*
X1542972Y296758D03*
X1532080Y310820D03*
X1582659Y334237D03*
X1587300Y338400D03*
X1535813Y326540D03*
X1545000Y336900D03*
X1576168Y313332D03*
X1555100Y356000D03*
X1549303Y358875D03*
X1585298Y383013D03*
X1576305Y371122D03*
X1580029Y356304D03*
X1576129Y377952D03*
X1546350Y363400D03*
X1565188Y351991D03*
X1585600Y375200D03*
X1543651Y368755D03*
X1540300Y371800D03*
X1534000Y371500D03*
X1536800Y367300D03*
X1528339Y372339D03*
X1529400Y367200D03*
X1554150Y371303D03*
X1585650Y389001D03*
X1578750Y391060D03*
X1571598Y355435D03*
X1580253Y383700D03*
X1575310Y444790D03*
X1581000Y465400D03*
X1583060Y449320D03*
X1578840Y473176D03*
X1584500Y579009D03*
X1585830Y592132D03*
X1556630Y610070D03*
X1541610Y593700D03*
X1571080Y591445D03*
X1569257Y614855D03*
X1567300Y601700D03*
X1594821Y31300D03*
X1608500Y-12800D03*
X1631500Y12200D03*
X1601200Y32300D03*
Y20000D03*
X1623400Y17500D03*
X1601502Y3437D03*
X1597244Y43700D03*
X1617688Y79904D03*
X1635841Y47859D03*
X1603000Y63000D03*
X1641000Y35500D03*
X1614000Y63500D03*
X1619750Y63650D03*
X1624500Y50890D03*
X1627330Y44800D03*
X1603900Y41300D03*
X1615400Y39800D03*
X1640000Y60000D03*
X1638580Y76500D03*
X1622000Y84500D03*
X1648700Y82100D03*
X1640732Y106227D03*
X1592510Y140471D03*
X1591700Y146200D03*
X1591366Y108251D03*
X1603804Y146096D03*
X1592700Y154600D03*
X1630300Y101900D03*
X1635384Y105507D03*
X1646200Y103800D03*
X1612103Y131920D03*
X1633994Y200254D03*
X1597302Y162132D03*
X1596730Y189030D03*
X1619958Y206643D03*
X1613002Y169672D03*
X1634170Y168900D03*
X1637825Y171672D03*
X1640910Y192600D03*
X1645395Y169192D03*
X1641375Y170017D03*
X1606538Y173091D03*
X1604326Y203326D03*
X1609116Y170006D03*
X1604275Y164859D03*
X1617078Y169100D03*
X1632000Y173800D03*
X1651064Y171331D03*
X1591606Y198319D03*
X1649621Y236279D03*
X1605200Y263833D03*
X1643750Y267900D03*
X1594500Y277500D03*
X1593250Y245553D03*
X1644700Y260900D03*
X1589954Y229054D03*
X1610550Y222670D03*
X1597000Y265900D03*
X1648911Y326711D03*
X1613000Y337900D03*
X1641055Y324176D03*
X1605090Y336004D03*
X1631419Y319313D03*
X1642022Y318523D03*
X1624900Y377400D03*
X1595076Y353237D03*
X1599300Y350200D03*
X1651163Y384645D03*
X1649530Y375170D03*
X1640000Y348800D03*
X1628843Y411524D03*
X1599539Y436752D03*
X1596800Y430500D03*
X1628439Y439800D03*
X1629913Y463000D03*
X1623300Y458910D03*
X1623527Y453915D03*
X1612500Y414700D03*
X1609138Y505050D03*
X1632762Y502957D03*
X1627500Y502000D03*
X1615307Y466679D03*
X1651486Y500217D03*
X1598013Y557397D03*
X1596200Y576250D03*
X1669500Y28500D03*
X1683210Y-10630D03*
X1700130Y77700D03*
X1662100Y85000D03*
X1666693Y95300D03*
X1679147Y78085D03*
X1670500Y64500D03*
X1694200Y44500D03*
X1694070Y64800D03*
X1703727Y74152D03*
X1667497Y47202D03*
X1663000Y76400D03*
X1667000Y56000D03*
X1678974Y51626D03*
X1682158Y59955D03*
X1680958Y66942D03*
X1692470Y69740D03*
X1688060Y43900D03*
X1665876Y62596D03*
X1673415Y94797D03*
X1662675Y106475D03*
X1672222Y98726D03*
X1667600Y106232D03*
X1654875Y115278D03*
X1713137Y213138D03*
X1653496Y167799D03*
X1660891Y169381D03*
X1708922Y204564D03*
X1701500Y208600D03*
X1656700Y171014D03*
X1708600Y182800D03*
X1656200Y199700D03*
X1677558Y189941D03*
X1681670Y169940D03*
X1710650Y176650D03*
X1671209Y176011D03*
X1665500Y226000D03*
X1656500Y247500D03*
X1674500Y228513D03*
X1689019Y253510D03*
X1665000Y254000D03*
X1668648Y265000D03*
X1669348Y240862D03*
X1655821Y236554D03*
X1666500Y231900D03*
X1661872Y338515D03*
X1654937Y338572D03*
X1661600Y333100D03*
X1668735Y344282D03*
X1653396Y390402D03*
X1680520Y445012D03*
X1665900Y447000D03*
X1681336Y457690D03*
X1658482Y498975D03*
X1656197Y503552D03*
X1701960Y585390D03*
X1705683Y589300D03*
X1762600Y15500D03*
X1774600Y8800D03*
X1769730Y10070D03*
X1728460Y71300D03*
X1735800Y54650D03*
X1741044Y65498D03*
X1759525Y56400D03*
X1743600Y43900D03*
X1736600Y44700D03*
X1735850Y49650D03*
X1731280Y89220D03*
X1757383Y63002D03*
X1745650Y91850D03*
X1764900Y91800D03*
X1727860Y93920D03*
X1753370Y88520D03*
X1744600Y150900D03*
X1760200Y108900D03*
X1765000Y102000D03*
X1764900Y97000D03*
X1721000Y193706D03*
X1718900Y448000D03*
X1718230Y452955D03*
X1768200Y505700D03*
X1715489Y493890D03*
X1771502Y501944D03*
X1738500Y581700D03*
X1738600Y565100D03*
X1728537Y589342D03*
X1716438Y600400D03*
X1748100Y607000D03*
X1744700Y593700D03*
X1782900Y9500D03*
X1833210Y-3910D03*
X1777685Y12830D03*
X1787164Y31113D03*
X1835600Y13000D03*
X1793720Y7387D03*
X1787969Y47993D03*
X1779440Y52250D03*
X1797840Y49720D03*
X1782949Y155900D03*
X1832177Y150500D03*
X1792000Y118100D03*
X1788000Y114500D03*
X1817767Y101100D03*
X1797620Y148240D03*
X1817715Y172398D03*
X1806032Y256368D03*
X1820341Y254616D03*
X1821100Y239200D03*
X1829971Y233712D03*
X1834500Y250000D03*
X1835900Y244600D03*
X1821600Y227200D03*
X1826662Y228000D03*
X1795358Y238669D03*
X1800728Y238920D03*
X1824850Y511050D03*
X1808134Y495734D03*
X1817950Y517500D03*
X1825600Y482100D03*
X1821441Y528960D03*
X1821895Y588200D03*
X1834700Y556500D03*
X1814138Y548444D03*
X1809290Y549668D03*
X1800683Y572968D03*
X1826600Y549500D03*
X1784650Y566000D03*
X1776200Y578650D03*
X1783400Y570900D03*
X1779950Y575300D03*
X1776400Y583900D03*
X1827211Y597431D03*
X1786450Y590040D03*
X1783200Y597400D03*
X1781600Y592600D03*
X1846500Y10500D03*
X1864706Y34766D03*
X1836800Y91000D03*
X1854482Y82583D03*
X1871460Y73390D03*
X1891494Y70584D03*
X1895000Y61600D03*
X1886800Y72500D03*
X1858700Y49700D03*
X1866100Y51600D03*
X1871812Y39088D03*
X1866376Y67105D03*
X1860100Y111500D03*
X1879700Y155700D03*
X1868844Y103130D03*
X1892000Y126500D03*
X1867400Y139050D03*
X1854477Y212365D03*
X1844110Y206600D03*
X1868000Y199100D03*
X1840783Y169326D03*
X1841900Y174200D03*
X1885719Y232386D03*
X1856422Y456400D03*
X1848511Y445558D03*
X1861312Y457446D03*
X1866900Y458400D03*
X1851150Y477640D03*
X1860500Y469800D03*
X1848200Y510500D03*
X1880242Y515942D03*
X1838843Y568874D03*
X1896800Y551900D03*
X1852190Y537760D03*
X1865300Y584950D03*
X1851600Y551400D03*
X1892554Y565000D03*
X1842730Y545224D03*
X1836909Y528586D03*
X1839200Y589619D03*
X1916660Y70070D03*
X1944740Y81810D03*
X1948458Y149021D03*
X1915700Y144200D03*
X1930000Y114608D03*
X1929800Y151900D03*
X1916700Y122700D03*
X1902370Y147000D03*
X1916400Y127900D03*
X1916700Y196700D03*
X1921100Y199269D03*
X1925520Y179160D03*
X1935300Y172600D03*
X1900230Y204500D03*
X1921900Y158100D03*
X1933900Y167600D03*
X1901400Y161200D03*
X1944173Y200444D03*
X1954070Y177088D03*
X1927300Y201000D03*
X1942345Y206525D03*
X1937800Y163000D03*
X1954143Y172000D03*
X1956890Y237126D03*
X1937430Y469860D03*
X1951800Y477900D03*
X1943500Y471000D03*
X1927138Y480071D03*
X1953440Y495050D03*
X1959300Y525500D03*
X1930402Y516640D03*
X1945170Y510870D03*
X1925800Y567500D03*
X1956100Y537500D03*
X1925808Y562498D03*
X1904800Y577700D03*
X1919500Y558900D03*
X1904790Y586240D03*
X1930625Y566185D03*
X1930600Y561000D03*
X1959100Y542500D03*
X1954350Y545350D03*
X1924800Y586400D03*
X1936970Y590600D03*
X1913180Y601923D03*
X1906900Y603200D03*
X1910150Y597900D03*
X1921700Y613500D03*
X1907240Y610410D03*
X1902800Y599200D03*
X1914500Y613600D03*
X1962780Y231794D03*
X1964281Y525057D03*
X1960078Y550793D03*
X1960700Y531600D03*
X1964100Y608000D03*
X1964300Y601900D03*
G54D36*
X48700Y255780D03*
X29000D03*
G54D147*
X1467570Y481702D03*
X1473246Y482312D03*
G54D129*
X1457000Y104700D03*
X1474100Y237800D03*
X1585849Y108488D03*
X1582849Y99488D03*
X1825700Y29700D03*
X1938600Y458717D03*
G54D148*
X1552100Y86000D03*
Y94000D03*
X1560900Y90000D03*
G54D139*
X1446392Y472057D03*
X1438283Y472592D03*
G54D82*
X594741Y135085D03*
G54D91*
X584181Y360208D03*
G54D55*
X83500Y229800D03*
Y234800D03*
Y239800D03*
Y224800D03*
G54D64*
X56872Y310550D03*
Y318050D03*
X48372Y314300D03*
X690704Y274026D03*
X682204Y277776D03*
Y270276D03*
X1497600Y164750D03*
Y172250D03*
X1489100Y168500D03*
X1518798Y166578D03*
Y174078D03*
X1510298Y170328D03*
X1628500Y31900D03*
Y24400D03*
X1637000Y28150D03*
X1648400Y67721D03*
Y60221D03*
X1648900Y53121D03*
Y45621D03*
X1652250Y275750D03*
X1643750Y279500D03*
X1652250Y283250D03*
X1646250Y311000D03*
X1656900Y63971D03*
X1657400Y49371D03*
X1654750Y307250D03*
Y314750D03*
X1743650Y74700D03*
X1735150Y78450D03*
X1743650Y82200D03*
X1774900Y599750D03*
X1766400Y603500D03*
Y596000D03*
X1893850Y575087D03*
Y582587D03*
X1885350Y578837D03*
X1904250Y556750D03*
X1912750Y553000D03*
X1904250Y549250D03*
G54D175*
X1699600Y235400D03*
Y454297D03*
X1866923Y235400D03*
X1955506Y454297D03*
G54D184*
X1761339Y536791D03*
X1757402D03*
X1753465D03*
X1749528D03*
X1745591D03*
X1741654D03*
X1761339D03*
X1757402D03*
X1753465D03*
X1749528D03*
X1745591D03*
X1741654D03*
G54D73*
X116927Y22133D03*
Y4023D03*
X120273Y22133D03*
X126966D03*
X133659D03*
X143699D03*
X150392D03*
X157084D03*
X163777D03*
X123620Y4023D03*
X130313D03*
X137006D03*
X147045D03*
X153738D03*
X160431D03*
X167124D03*
X137006Y22133D03*
X140352D03*
X143699Y4023D03*
X140352D03*
X120273D03*
X167124Y22133D03*
X150392Y4023D03*
X147045Y22133D03*
X126966Y4023D03*
X123620Y22133D03*
X157084Y4023D03*
X153738Y22133D03*
X133659Y4023D03*
X163777D03*
X160431Y22133D03*
X130313D03*
X116927Y59933D03*
Y41823D03*
X120273Y59933D03*
X126966D03*
X133659D03*
X143699D03*
X150392D03*
X157084D03*
X163777D03*
X123620Y41823D03*
X130313D03*
X137006D03*
X147045D03*
X153738D03*
X160431D03*
X167124D03*
X137006Y59933D03*
X140352D03*
X143699Y41823D03*
X140352D03*
X120273D03*
X167124Y59933D03*
X150392Y41823D03*
X147045Y59933D03*
X126966Y41823D03*
X123620Y59933D03*
X157084Y41823D03*
X153738Y59933D03*
X133659Y41823D03*
X163777D03*
X160431Y59933D03*
X130313D03*
X116927Y97733D03*
Y79623D03*
X120273Y97733D03*
X126966D03*
X133659D03*
X143699D03*
X150392D03*
X157084D03*
X163777D03*
X123620Y79623D03*
X130313D03*
X137006D03*
X147045D03*
X153738D03*
X160431D03*
X167124D03*
X137006Y97733D03*
X140352D03*
X143699Y79623D03*
X140352D03*
X120273D03*
X167124Y97733D03*
X150392Y79623D03*
X147045Y97733D03*
X126966Y79623D03*
X123620Y97733D03*
X157084Y79623D03*
X153738Y97733D03*
X133659Y79623D03*
X163777D03*
X160431Y97733D03*
X130313D03*
X167124Y505024D03*
X163777D03*
X160431D03*
X157084D03*
X153738D03*
X150392D03*
X147045D03*
X143699D03*
X140352D03*
X137006D03*
X133659D03*
X130313D03*
X126966D03*
X123620D03*
X120273D03*
X116927D03*
X167124Y523134D03*
X163777D03*
X160431D03*
X157084D03*
X153738D03*
X150392D03*
X147045D03*
X143699D03*
X140352D03*
X137006D03*
X133659D03*
X130313D03*
X126966D03*
X123620D03*
X120273D03*
X116927D03*
X167124Y580624D03*
X163777D03*
X160431D03*
X157084D03*
X153738D03*
X150392D03*
X147045D03*
X143699D03*
X140352D03*
X137006D03*
X133659D03*
X130313D03*
X126966D03*
X123620D03*
X120273D03*
X116927D03*
X167124Y542824D03*
X163777D03*
X160431D03*
X157084D03*
X153738D03*
X150392D03*
X147045D03*
X143699D03*
X140352D03*
X137006D03*
X133659D03*
X130313D03*
X126966D03*
X123620D03*
X120273D03*
X116927D03*
X167124Y560934D03*
X163777D03*
X160431D03*
X157084D03*
X153738D03*
X150392D03*
X147045D03*
X143699D03*
X140352D03*
X137006D03*
X133659D03*
X130313D03*
X126966D03*
X123620D03*
X120273D03*
X116927D03*
X167124Y598734D03*
X163777D03*
X160431D03*
X157084D03*
X153738D03*
X150392D03*
X147045D03*
X143699D03*
X140352D03*
X137006D03*
X133659D03*
X130313D03*
X126966D03*
X123620D03*
X120273D03*
X116927D03*
X170470Y22133D03*
X180510D03*
X187203D03*
X193896D03*
X200588D03*
X207281D03*
X217321D03*
X224014D03*
X230707D03*
X173817Y4023D03*
X183856D03*
X190549D03*
X197242D03*
X203935D03*
X210628D03*
X220667D03*
X227360D03*
X217321D03*
X213974D03*
X180510D03*
X177163D03*
X210628Y22133D03*
X213974D03*
X173817D03*
X177163D03*
X170470Y4023D03*
X224014D03*
X220667Y22133D03*
X200588Y4023D03*
X197242Y22133D03*
X230707Y4023D03*
X227360Y22133D03*
X207281Y4023D03*
X203935Y22133D03*
X187203Y4023D03*
X183856Y22133D03*
X193896Y4023D03*
X190549Y22133D03*
X170470Y59933D03*
X180510D03*
X187203D03*
X193896D03*
X200588D03*
X207281D03*
X217321D03*
X224014D03*
X230707D03*
X173817Y41823D03*
X183856D03*
X190549D03*
X197242D03*
X203935D03*
X210628D03*
X220667D03*
X227360D03*
X217321D03*
X213974D03*
X180510D03*
X177163D03*
X210628Y59933D03*
X213974D03*
X173817D03*
X177163D03*
X170470Y41823D03*
X224014D03*
X220667Y59933D03*
X200588Y41823D03*
X197242Y59933D03*
X230707Y41823D03*
X227360Y59933D03*
X207281Y41823D03*
X203935Y59933D03*
X187203Y41823D03*
X183856Y59933D03*
X193896Y41823D03*
X190549Y59933D03*
X170470Y97733D03*
X180510D03*
X187203D03*
X193896D03*
X200588D03*
X207281D03*
X217321D03*
X224014D03*
X230707D03*
X173817Y79623D03*
X183856D03*
X190549D03*
X197242D03*
X203935D03*
X210628D03*
X220667D03*
X227360D03*
X217321D03*
X213974D03*
X180510D03*
X177163D03*
X210628Y97733D03*
X213974D03*
X173817D03*
X177163D03*
X170470Y79623D03*
X224014D03*
X220667Y97733D03*
X200588Y79623D03*
X197242Y97733D03*
X230707Y79623D03*
X227360Y97733D03*
X207281Y79623D03*
X203935Y97733D03*
X187203Y79623D03*
X183856Y97733D03*
X193896Y79623D03*
X190549Y97733D03*
X230707Y505024D03*
X227360D03*
X224014D03*
X220667D03*
X217321D03*
X213974D03*
X210628D03*
X207281D03*
X203935D03*
X200588D03*
X197242D03*
X193896D03*
X190549D03*
X187203D03*
X183856D03*
X180510D03*
X177163D03*
X173817D03*
X170470D03*
X230707Y523134D03*
X227360D03*
X224014D03*
X220667D03*
X217321D03*
X213974D03*
X210628D03*
X207281D03*
X203935D03*
X200588D03*
X197242D03*
X193896D03*
X190549D03*
X187203D03*
X183856D03*
X180510D03*
X177163D03*
X173817D03*
X170470D03*
X230707Y580624D03*
X227360D03*
X224014D03*
X220667D03*
X217321D03*
X213974D03*
X210628D03*
X207281D03*
X203935D03*
X200588D03*
X197242D03*
X193896D03*
X190549D03*
X187203D03*
X183856D03*
X180510D03*
X177163D03*
X173817D03*
X170470D03*
X230707Y542824D03*
X227360D03*
X224014D03*
X220667D03*
X217321D03*
X213974D03*
X210628D03*
X207281D03*
X203935D03*
X200588D03*
X197242D03*
X193896D03*
X190549D03*
X187203D03*
X183856D03*
X180510D03*
X177163D03*
X173817D03*
X170470D03*
X230707Y560934D03*
X227360D03*
X224014D03*
X220667D03*
X217321D03*
X213974D03*
X210628D03*
X207281D03*
X203935D03*
X200588D03*
X197242D03*
X193896D03*
X190549D03*
X187203D03*
X183856D03*
X180510D03*
X177163D03*
X173817D03*
X170470D03*
X230707Y598734D03*
X227360D03*
X224014D03*
X220667D03*
X217321D03*
X213974D03*
X210628D03*
X207281D03*
X203935D03*
X200588D03*
X197242D03*
X193896D03*
X190549D03*
X187203D03*
X183856D03*
X180510D03*
X177163D03*
X173817D03*
X170470D03*
X237399Y22133D03*
X244092D03*
X254132D03*
X260825D03*
X267518D03*
X274210D03*
X280903D03*
X290943D03*
X234053Y4023D03*
X240746D03*
X247439D03*
X257478D03*
X264171D03*
X270864D03*
X277557D03*
X284250D03*
X290943D03*
X287596D03*
X254132D03*
X250785D03*
X284250Y22133D03*
X287596D03*
X247439D03*
X250785D03*
X260825Y4023D03*
X257478Y22133D03*
X237399Y4023D03*
X234053Y22133D03*
X267518Y4023D03*
X264171Y22133D03*
X244092Y4023D03*
X240746Y22133D03*
X274210Y4023D03*
X270864Y22133D03*
X280903Y4023D03*
X277557Y22133D03*
X237399Y59933D03*
X244092D03*
X254132D03*
X260825D03*
X267518D03*
X274210D03*
X280903D03*
X290943D03*
X234053Y41823D03*
X240746D03*
X247439D03*
X257478D03*
X264171D03*
X270864D03*
X277557D03*
X284250D03*
X290943D03*
X287596D03*
X254132D03*
X250785D03*
X284250Y59933D03*
X287596D03*
X247439D03*
X250785D03*
X260825Y41823D03*
X257478Y59933D03*
X237399Y41823D03*
X234053Y59933D03*
X267518Y41823D03*
X264171Y59933D03*
X244092Y41823D03*
X240746Y59933D03*
X274210Y41823D03*
X270864Y59933D03*
X280903Y41823D03*
X277557Y59933D03*
X237399Y97733D03*
X244092D03*
X254132D03*
X260825D03*
X267518D03*
X274210D03*
X280903D03*
X290943D03*
X234053Y79623D03*
X240746D03*
X247439D03*
X257478D03*
X264171D03*
X270864D03*
X277557D03*
X284250D03*
X290943D03*
X287596D03*
X254132D03*
X250785D03*
X284250Y97733D03*
X287596D03*
X247439D03*
X250785D03*
X260825Y79623D03*
X257478Y97733D03*
X237399Y79623D03*
X234053Y97733D03*
X267518Y79623D03*
X264171Y97733D03*
X244092Y79623D03*
X240746Y97733D03*
X274210Y79623D03*
X270864Y97733D03*
X280903Y79623D03*
X277557Y97733D03*
X290943Y505024D03*
X287596D03*
X284250D03*
X280903D03*
X277557D03*
X274210D03*
X270864D03*
X267518D03*
X264171D03*
X260825D03*
X257478D03*
X254132D03*
X250785D03*
X247439D03*
X244092D03*
X240746D03*
X237399D03*
X234053D03*
X290943Y523134D03*
X287596D03*
X284250D03*
X280903D03*
X277557D03*
X274210D03*
X270864D03*
X267518D03*
X264171D03*
X260825D03*
X257478D03*
X254132D03*
X250785D03*
X247439D03*
X244092D03*
X240746D03*
X237399D03*
X234053D03*
X290943Y580624D03*
X287596D03*
X284250D03*
X280903D03*
X277557D03*
X274210D03*
X270864D03*
X267518D03*
X264171D03*
X260825D03*
X257478D03*
X254132D03*
X250785D03*
X247439D03*
X244092D03*
X240746D03*
X237399D03*
X234053D03*
X290943Y542824D03*
X287596D03*
X284250D03*
X280903D03*
X277557D03*
X274210D03*
X270864D03*
X267518D03*
X264171D03*
X260825D03*
X257478D03*
X254132D03*
X250785D03*
X247439D03*
X244092D03*
X240746D03*
X237399D03*
X234053D03*
X290943Y560934D03*
X287596D03*
X284250D03*
X280903D03*
X277557D03*
X274210D03*
X270864D03*
X267518D03*
X264171D03*
X260825D03*
X257478D03*
X254132D03*
X250785D03*
X247439D03*
X244092D03*
X240746D03*
X237399D03*
X234053D03*
X290943Y598734D03*
X287596D03*
X284250D03*
X280903D03*
X277557D03*
X274210D03*
X270864D03*
X267518D03*
X264171D03*
X260825D03*
X257478D03*
X254132D03*
X250785D03*
X247439D03*
X244092D03*
X240746D03*
X237399D03*
X234053D03*
X341140Y4023D03*
X351179D03*
X311021Y22133D03*
X317714D03*
X327754D03*
X337793D03*
X347833D03*
X314368Y4023D03*
X321061D03*
X331100D03*
X297636Y22133D03*
X304329D03*
X294289Y4023D03*
X300982D03*
X307675D03*
X317714D03*
X307675Y22133D03*
X311021Y4023D03*
X314368Y22133D03*
X297636Y4023D03*
X294289Y22133D03*
X304329Y4023D03*
X300982Y22133D03*
X324407Y4023D03*
Y22133D03*
X327754Y4023D03*
X321061Y22133D03*
X334447D03*
X341140D03*
X337793Y4023D03*
X344486Y22133D03*
Y4023D03*
X347833D03*
X351179Y22133D03*
X354525Y4023D03*
X331100Y22133D03*
X334447Y4023D03*
X354525Y22133D03*
X341140Y41823D03*
X351179D03*
X311021Y59933D03*
X317714D03*
X327754D03*
X337793D03*
X347833D03*
X314368Y41823D03*
X321061D03*
X331100D03*
X297636Y59933D03*
X304329D03*
X294289Y41823D03*
X300982D03*
X307675D03*
X317714D03*
X307675Y59933D03*
X311021Y41823D03*
X314368Y59933D03*
X297636Y41823D03*
X294289Y59933D03*
X304329Y41823D03*
X300982Y59933D03*
X324407Y41823D03*
Y59933D03*
X327754Y41823D03*
X321061Y59933D03*
X334447D03*
X341140D03*
X337793Y41823D03*
X344486Y59933D03*
Y41823D03*
X347833D03*
X351179Y59933D03*
X354525Y41823D03*
X331100Y59933D03*
X334447Y41823D03*
X354525Y59933D03*
X341140Y79623D03*
X351179D03*
X311021Y97733D03*
X317714D03*
X327754D03*
X337793D03*
X347833D03*
X314368Y79623D03*
X321061D03*
X331100D03*
X297636Y97733D03*
X304329D03*
X294289Y79623D03*
X300982D03*
X307675D03*
X317714D03*
X307675Y97733D03*
X311021Y79623D03*
X314368Y97733D03*
X297636Y79623D03*
X294289Y97733D03*
X304329Y79623D03*
X300982Y97733D03*
X324407Y79623D03*
Y97733D03*
X327754Y79623D03*
X321061Y97733D03*
X334447D03*
X341140D03*
X337793Y79623D03*
X344486Y97733D03*
Y79623D03*
X347833D03*
X351179Y97733D03*
X354525Y79623D03*
X331100Y97733D03*
X334447Y79623D03*
X354525Y97733D03*
Y505024D03*
X351179D03*
X347833D03*
X344486D03*
X341140D03*
X337793D03*
X334447D03*
X331100D03*
X327754D03*
X324407D03*
X321061D03*
X317714D03*
X314368D03*
X311021D03*
X307675D03*
X304329D03*
X300982D03*
X297636D03*
X294289D03*
X354525Y523134D03*
X351179D03*
X347833D03*
X344486D03*
X341140D03*
X337793D03*
X334447D03*
X331100D03*
X327754D03*
X324407D03*
X321061D03*
X317714D03*
X314368D03*
X311021D03*
X307675D03*
X304329D03*
X300982D03*
X297636D03*
X294289D03*
X354525Y580624D03*
X351179D03*
X347833D03*
X344486D03*
X341140D03*
X337793D03*
X334447D03*
X331100D03*
X327754D03*
X324407D03*
X321061D03*
X317714D03*
X314368D03*
X311021D03*
X307675D03*
X304329D03*
X300982D03*
X297636D03*
X294289D03*
X354525Y542824D03*
X351179D03*
X347833D03*
X344486D03*
X341140D03*
X337793D03*
X334447D03*
X331100D03*
X327754D03*
X324407D03*
X321061D03*
X317714D03*
X314368D03*
X311021D03*
X307675D03*
X304329D03*
X300982D03*
X297636D03*
X294289D03*
X354525Y560934D03*
X351179D03*
X347833D03*
X344486D03*
X341140D03*
X337793D03*
X334447D03*
X331100D03*
X327754D03*
X324407D03*
X321061D03*
X317714D03*
X314368D03*
X311021D03*
X307675D03*
X304329D03*
X300982D03*
X297636D03*
X294289D03*
X354525Y598734D03*
X351179D03*
X347833D03*
X344486D03*
X341140D03*
X337793D03*
X334447D03*
X331100D03*
X327754D03*
X324407D03*
X321061D03*
X317714D03*
X314368D03*
X311021D03*
X307675D03*
X304329D03*
X300982D03*
X297636D03*
X294289D03*
X371258Y22133D03*
Y4023D03*
X357872D03*
X367911D03*
X398029D03*
X408069D03*
X357872Y22133D03*
X367911D03*
X401376D03*
X411415D03*
X414762D03*
X411415Y4023D03*
X394683D03*
Y22133D03*
X361218Y4023D03*
X364565D03*
X361218Y22133D03*
X364565D03*
X401376Y4023D03*
X404722Y22133D03*
X408069D03*
X414762Y4023D03*
X404722D03*
X398029Y22133D03*
X371258Y59933D03*
Y41823D03*
X357872D03*
X367911D03*
X398029D03*
X408069D03*
X357872Y59933D03*
X367911D03*
X401376D03*
X411415D03*
X414762D03*
X411415Y41823D03*
X394683D03*
Y59933D03*
X361218Y41823D03*
X364565D03*
X361218Y59933D03*
X364565D03*
X401376Y41823D03*
X404722Y59933D03*
X408069D03*
X414762Y41823D03*
X404722D03*
X398029Y59933D03*
X371258Y97733D03*
Y79623D03*
X357872D03*
X367911D03*
X398029D03*
X408069D03*
X357872Y97733D03*
X367911D03*
X401376D03*
X411415D03*
X414762D03*
X411415Y79623D03*
X394683D03*
Y97733D03*
X361218Y79623D03*
X364565D03*
X361218Y97733D03*
X364565D03*
X401376Y79623D03*
X404722Y97733D03*
X408069D03*
X414762Y79623D03*
X404722D03*
X398029Y97733D03*
X414762Y505024D03*
X411415D03*
X408069D03*
X404722D03*
X401376D03*
X398029D03*
X394683D03*
X371258D03*
X367911D03*
X364565D03*
X361218D03*
X357872D03*
X414762Y523134D03*
X411415D03*
X408069D03*
X404722D03*
X401376D03*
X398029D03*
X394683D03*
X371258D03*
X367911D03*
X364565D03*
X361218D03*
X357872D03*
X414762Y580624D03*
X411415D03*
X408069D03*
X404722D03*
X401376D03*
X398029D03*
X394683D03*
X371258D03*
X367911D03*
X364565D03*
X361218D03*
X357872D03*
X414762Y542824D03*
X411415D03*
X408069D03*
X404722D03*
X401376D03*
X398029D03*
X394683D03*
X371258D03*
X367911D03*
X364565D03*
X361218D03*
X357872D03*
X414762Y560934D03*
X411415D03*
X408069D03*
X404722D03*
X401376D03*
X398029D03*
X394683D03*
X371258D03*
X367911D03*
X364565D03*
X361218D03*
X357872D03*
X414762Y598734D03*
X411415D03*
X408069D03*
X404722D03*
X401376D03*
X398029D03*
X394683D03*
X371258D03*
X367911D03*
X364565D03*
X361218D03*
X357872D03*
X418108Y4023D03*
X424801D03*
X431494D03*
X418108Y22133D03*
X428147D03*
X434840D03*
X441533D03*
Y4023D03*
X448226Y22133D03*
X454919D03*
X461612D03*
X471651D03*
X478344D03*
X451573Y4023D03*
X458266D03*
X464958D03*
X474998D03*
X471651D03*
X468305D03*
X464958Y22133D03*
X468305D03*
X421455Y4023D03*
X448226D03*
X444880D03*
Y22133D03*
X431494D03*
X438187D03*
X424801D03*
X478344Y4023D03*
X474998Y22133D03*
X454919Y4023D03*
X451573Y22133D03*
X461612Y4023D03*
X458266Y22133D03*
X438187Y4023D03*
X434840D03*
X421455Y22133D03*
X428147Y4023D03*
X418108Y41823D03*
X424801D03*
X431494D03*
X418108Y59933D03*
X428147D03*
X434840D03*
X441533D03*
Y41823D03*
X448226Y59933D03*
X454919D03*
X461612D03*
X471651D03*
X478344D03*
X451573Y41823D03*
X458266D03*
X464958D03*
X474998D03*
X471651D03*
X468305D03*
X464958Y59933D03*
X468305D03*
X421455Y41823D03*
X448226D03*
X444880D03*
Y59933D03*
X431494D03*
X438187D03*
X424801D03*
X478344Y41823D03*
X474998Y59933D03*
X454919Y41823D03*
X451573Y59933D03*
X461612Y41823D03*
X458266Y59933D03*
X438187Y41823D03*
X434840D03*
X421455Y59933D03*
X428147Y41823D03*
X418108Y79623D03*
X424801D03*
X431494D03*
X418108Y97733D03*
X428147D03*
X434840D03*
X441533D03*
Y79623D03*
X448226Y97733D03*
X454919D03*
X461612D03*
X471651D03*
X478344D03*
X451573Y79623D03*
X458266D03*
X464958D03*
X474998D03*
X471651D03*
X468305D03*
X464958Y97733D03*
X468305D03*
X421455Y79623D03*
X448226D03*
X444880D03*
Y97733D03*
X431494D03*
X438187D03*
X424801D03*
X478344Y79623D03*
X474998Y97733D03*
X454919Y79623D03*
X451573Y97733D03*
X461612Y79623D03*
X458266Y97733D03*
X438187Y79623D03*
X434840D03*
X421455Y97733D03*
X428147Y79623D03*
X478344Y505024D03*
X474998D03*
X471651D03*
X468305D03*
X464958D03*
X461612D03*
X458266D03*
X454919D03*
X451573D03*
X448226D03*
X444880D03*
X441533D03*
X438187D03*
X434840D03*
X431494D03*
X428147D03*
X424801D03*
X421455D03*
X418108D03*
X478344Y523134D03*
X474998D03*
X471651D03*
X468305D03*
X464958D03*
X461612D03*
X458266D03*
X454919D03*
X451573D03*
X448226D03*
X444880D03*
X441533D03*
X438187D03*
X434840D03*
X431494D03*
X428147D03*
X424801D03*
X421455D03*
X418108D03*
X478344Y580624D03*
X474998D03*
X471651D03*
X468305D03*
X464958D03*
X461612D03*
X458266D03*
X454919D03*
X451573D03*
X448226D03*
X444880D03*
X441533D03*
X438187D03*
X434840D03*
X431494D03*
X428147D03*
X424801D03*
X421455D03*
X418108D03*
X478344Y542824D03*
X474998D03*
X471651D03*
X468305D03*
X464958D03*
X461612D03*
X458266D03*
X454919D03*
X451573D03*
X448226D03*
X444880D03*
X441533D03*
X438187D03*
X434840D03*
X431494D03*
X428147D03*
X424801D03*
X421455D03*
X418108D03*
X478344Y560934D03*
X474998D03*
X471651D03*
X468305D03*
X464958D03*
X461612D03*
X458266D03*
X454919D03*
X451573D03*
X448226D03*
X444880D03*
X441533D03*
X438187D03*
X434840D03*
X431494D03*
X428147D03*
X424801D03*
X421455D03*
X418108D03*
X478344Y598734D03*
X474998D03*
X471651D03*
X468305D03*
X464958D03*
X461612D03*
X458266D03*
X454919D03*
X451573D03*
X448226D03*
X444880D03*
X441533D03*
X438187D03*
X434840D03*
X431494D03*
X428147D03*
X424801D03*
X421455D03*
X418108D03*
X531888Y4023D03*
X538581D03*
X485037Y22133D03*
X491730D03*
X498423D03*
X508462D03*
X515155D03*
X521848D03*
X528541D03*
X535234D03*
X481691Y4023D03*
X488384D03*
X495077D03*
X501770D03*
X511809D03*
X518502D03*
X525195D03*
X508462D03*
X505116D03*
X538581Y22133D03*
X501770D03*
X505116D03*
X528541Y4023D03*
X525195Y22133D03*
X535234Y4023D03*
X531888Y22133D03*
X515155Y4023D03*
X511809Y22133D03*
X491730Y4023D03*
X488384Y22133D03*
X521848Y4023D03*
X518502Y22133D03*
X498423Y4023D03*
X495077Y22133D03*
X485037Y4023D03*
X481691Y22133D03*
X531888Y41823D03*
X538581D03*
X485037Y59933D03*
X491730D03*
X498423D03*
X508462D03*
X515155D03*
X521848D03*
X528541D03*
X535234D03*
X481691Y41823D03*
X488384D03*
X495077D03*
X501770D03*
X511809D03*
X518502D03*
X525195D03*
X508462D03*
X505116D03*
X538581Y59933D03*
X501770D03*
X505116D03*
X528541Y41823D03*
X525195Y59933D03*
X535234Y41823D03*
X531888Y59933D03*
X515155Y41823D03*
X511809Y59933D03*
X491730Y41823D03*
X488384Y59933D03*
X521848Y41823D03*
X518502Y59933D03*
X498423Y41823D03*
X495077Y59933D03*
X485037Y41823D03*
X481691Y59933D03*
X531888Y79623D03*
X538581D03*
X485037Y97733D03*
X491730D03*
X498423D03*
X508462D03*
X515155D03*
X521848D03*
X528541D03*
X535234D03*
X481691Y79623D03*
X488384D03*
X495077D03*
X501770D03*
X511809D03*
X518502D03*
X525195D03*
X508462D03*
X505116D03*
X538581Y97733D03*
X501770D03*
X505116D03*
X528541Y79623D03*
X525195Y97733D03*
X535234Y79623D03*
X531888Y97733D03*
X515155Y79623D03*
X511809Y97733D03*
X491730Y79623D03*
X488384Y97733D03*
X521848Y79623D03*
X518502Y97733D03*
X498423Y79623D03*
X495077Y97733D03*
X485037Y79623D03*
X481691Y97733D03*
X538581Y505024D03*
X535234D03*
X531888D03*
X528541D03*
X525195D03*
X521848D03*
X518502D03*
X515155D03*
X511809D03*
X508462D03*
X505116D03*
X501770D03*
X498423D03*
X495077D03*
X491730D03*
X488384D03*
X485037D03*
X481691D03*
X538581Y523134D03*
X535234D03*
X531888D03*
X528541D03*
X525195D03*
X521848D03*
X518502D03*
X515155D03*
X511809D03*
X508462D03*
X505116D03*
X501770D03*
X498423D03*
X495077D03*
X491730D03*
X488384D03*
X485037D03*
X481691D03*
X538581Y580624D03*
X535234D03*
X531888D03*
X528541D03*
X525195D03*
X521848D03*
X518502D03*
X515155D03*
X511809D03*
X508462D03*
X505116D03*
X501770D03*
X498423D03*
X495077D03*
X491730D03*
X488384D03*
X485037D03*
X481691D03*
X538581Y542824D03*
X535234D03*
X531888D03*
X528541D03*
X525195D03*
X521848D03*
X518502D03*
X515155D03*
X511809D03*
X508462D03*
X505116D03*
X501770D03*
X498423D03*
X495077D03*
X491730D03*
X488384D03*
X485037D03*
X481691D03*
X538581Y560934D03*
X535234D03*
X531888D03*
X528541D03*
X525195D03*
X521848D03*
X518502D03*
X515155D03*
X511809D03*
X508462D03*
X505116D03*
X501770D03*
X498423D03*
X495077D03*
X491730D03*
X488384D03*
X485037D03*
X481691D03*
X538581Y598734D03*
X535234D03*
X531888D03*
X528541D03*
X525195D03*
X521848D03*
X518502D03*
X515155D03*
X511809D03*
X508462D03*
X505116D03*
X501770D03*
X498423D03*
X495077D03*
X491730D03*
X488384D03*
X485037D03*
X481691D03*
X548620Y4023D03*
X555313D03*
X562006D03*
X545273Y22133D03*
X551966D03*
X558659D03*
X565352D03*
X572045D03*
X568699Y4023D03*
X582084Y22133D03*
X588777D03*
X595470D03*
X575392Y4023D03*
X585431D03*
X592124D03*
X598817D03*
X582084D03*
X578738D03*
X545273D03*
X541927D03*
X575392Y22133D03*
X578738D03*
X541927D03*
X602163Y4023D03*
Y22133D03*
X598817D03*
X588777Y4023D03*
X585431Y22133D03*
X565352Y4023D03*
X562006Y22133D03*
X595470Y4023D03*
X592124Y22133D03*
X572045Y4023D03*
X568699Y22133D03*
X551966Y4023D03*
X548620Y22133D03*
X558659Y4023D03*
X555313Y22133D03*
X548620Y41823D03*
X555313D03*
X562006D03*
X545273Y59933D03*
X551966D03*
X558659D03*
X565352D03*
X572045D03*
X568699Y41823D03*
X582084Y59933D03*
X588777D03*
X595470D03*
X575392Y41823D03*
X585431D03*
X592124D03*
X598817D03*
X582084D03*
X578738D03*
X545273D03*
X541927D03*
X575392Y59933D03*
X578738D03*
X541927D03*
X602163Y41823D03*
Y59933D03*
X598817D03*
X588777Y41823D03*
X585431Y59933D03*
X565352Y41823D03*
X562006Y59933D03*
X595470Y41823D03*
X592124Y59933D03*
X572045Y41823D03*
X568699Y59933D03*
X551966Y41823D03*
X548620Y59933D03*
X558659Y41823D03*
X555313Y59933D03*
X548620Y79623D03*
X555313D03*
X562006D03*
X545273Y97733D03*
X551966D03*
X558659D03*
X565352D03*
X572045D03*
X568699Y79623D03*
X582084Y97733D03*
X588777D03*
X595470D03*
X575392Y79623D03*
X585431D03*
X592124D03*
X598817D03*
X582084D03*
X578738D03*
X545273D03*
X541927D03*
X575392Y97733D03*
X578738D03*
X541927D03*
X602163Y79623D03*
Y97733D03*
X598817D03*
X588777Y79623D03*
X585431Y97733D03*
X565352Y79623D03*
X562006Y97733D03*
X595470Y79623D03*
X592124Y97733D03*
X572045Y79623D03*
X568699Y97733D03*
X551966Y79623D03*
X548620Y97733D03*
X558659Y79623D03*
X555313Y97733D03*
X602163Y505024D03*
X598817D03*
X595470D03*
X592124D03*
X588777D03*
X585431D03*
X582084D03*
X578738D03*
X575392D03*
X572045D03*
X568699D03*
X565352D03*
X562006D03*
X558659D03*
X555313D03*
X551966D03*
X548620D03*
X545273D03*
X541927D03*
X602163Y523134D03*
X598817D03*
X595470D03*
X592124D03*
X588777D03*
X585431D03*
X582084D03*
X578738D03*
X575392D03*
X572045D03*
X568699D03*
X565352D03*
X562006D03*
X558659D03*
X555313D03*
X551966D03*
X548620D03*
X545273D03*
X541927D03*
X602163Y580624D03*
X598817D03*
X595470D03*
X592124D03*
X588777D03*
X585431D03*
X582084D03*
X578738D03*
X575392D03*
X572045D03*
X568699D03*
X565352D03*
X562006D03*
X558659D03*
X555313D03*
X551966D03*
X548620D03*
X545273D03*
X541927D03*
X602163Y542824D03*
X598817D03*
X595470D03*
X592124D03*
X588777D03*
X585431D03*
X582084D03*
X578738D03*
X575392D03*
X572045D03*
X568699D03*
X565352D03*
X562006D03*
X558659D03*
X555313D03*
X551966D03*
X548620D03*
X545273D03*
X541927D03*
X602163Y560934D03*
X598817D03*
X595470D03*
X592124D03*
X588777D03*
X585431D03*
X582084D03*
X578738D03*
X575392D03*
X572045D03*
X568699D03*
X565352D03*
X562006D03*
X558659D03*
X555313D03*
X551966D03*
X548620D03*
X545273D03*
X541927D03*
X602163Y598734D03*
X598817D03*
X595470D03*
X592124D03*
X588777D03*
X585431D03*
X582084D03*
X578738D03*
X575392D03*
X572045D03*
X568699D03*
X565352D03*
X562006D03*
X558659D03*
X555313D03*
X551966D03*
X548620D03*
X545273D03*
X541927D03*
X608856Y22133D03*
X612203D03*
X615549Y4023D03*
X608856D03*
X612203D03*
X605510D03*
Y22133D03*
X615549D03*
X608856Y59933D03*
X612203D03*
X615549Y41823D03*
X608856D03*
X612203D03*
X605510D03*
Y59933D03*
X615549D03*
X608856Y97733D03*
X612203D03*
X615549Y79623D03*
X608856D03*
X612203D03*
X605510D03*
Y97733D03*
X615549D03*
Y505024D03*
X612203D03*
X608856D03*
X605510D03*
X615549Y523134D03*
X612203D03*
X608856D03*
X605510D03*
X615549Y580624D03*
X612203D03*
X608856D03*
X605510D03*
X615549Y542824D03*
X612203D03*
X608856D03*
X605510D03*
X615549Y560934D03*
X612203D03*
X608856D03*
X605510D03*
X615549Y598734D03*
X612203D03*
X608856D03*
X605510D03*
X786616Y4023D03*
X783269D03*
X779923D03*
X776576D03*
X773230D03*
X769883D03*
X766537D03*
X786616Y22133D03*
X783269D03*
X779923D03*
X776576D03*
X773230D03*
X769883D03*
X766537D03*
X786616Y79623D03*
X783269D03*
X779923D03*
X776576D03*
X773230D03*
X769883D03*
X766537D03*
X786616Y97733D03*
X783269D03*
X779923D03*
X776576D03*
X773230D03*
X769883D03*
X766537D03*
X786616Y41823D03*
X783269D03*
X779923D03*
X776576D03*
X773230D03*
X769883D03*
X766537D03*
X786616Y59933D03*
X783269D03*
X779923D03*
X776576D03*
X773230D03*
X769883D03*
X766537D03*
X786616Y505024D03*
X783269D03*
X779923D03*
X776576D03*
X773230D03*
X769883D03*
X766537D03*
X786616Y523134D03*
X783269D03*
X779923D03*
X776576D03*
X773230D03*
X769883D03*
X766537D03*
X786616Y580624D03*
X783269D03*
X779923D03*
X776576D03*
X773230D03*
X769883D03*
X766537D03*
X786616Y542824D03*
X783269D03*
X779923D03*
X776576D03*
X773230D03*
X769883D03*
X766537D03*
X786616Y560934D03*
X783269D03*
X779923D03*
X776576D03*
X773230D03*
X769883D03*
X766537D03*
X786616Y598734D03*
X783269D03*
X779923D03*
X776576D03*
X773230D03*
X769883D03*
X766537D03*
X846852Y4023D03*
X843506D03*
X840159D03*
X836813D03*
X833466D03*
X830120D03*
X826773D03*
X823427D03*
X820080D03*
X816734D03*
X813387D03*
X810041D03*
X806694D03*
X803348D03*
X800002D03*
X796655D03*
X793309D03*
X789962D03*
X846852Y22133D03*
X843506D03*
X840159D03*
X836813D03*
X833466D03*
X830120D03*
X826773D03*
X823427D03*
X820080D03*
X816734D03*
X813387D03*
X810041D03*
X806694D03*
X803348D03*
X800002D03*
X796655D03*
X793309D03*
X789962D03*
X846852Y79623D03*
X843506D03*
X840159D03*
X836813D03*
X833466D03*
X830120D03*
X826773D03*
X823427D03*
X820080D03*
X816734D03*
X813387D03*
X810041D03*
X806694D03*
X803348D03*
X800002D03*
X796655D03*
X793309D03*
X789962D03*
X846852Y97733D03*
X843506D03*
X840159D03*
X836813D03*
X833466D03*
X830120D03*
X826773D03*
X823427D03*
X820080D03*
X816734D03*
X813387D03*
X810041D03*
X806694D03*
X803348D03*
X800002D03*
X796655D03*
X793309D03*
X789962D03*
X846852Y41823D03*
X843506D03*
X840159D03*
X836813D03*
X833466D03*
X830120D03*
X826773D03*
X823427D03*
X820080D03*
X816734D03*
X813387D03*
X810041D03*
X806694D03*
X803348D03*
X800002D03*
X796655D03*
X793309D03*
X789962D03*
X846852Y59933D03*
X843506D03*
X840159D03*
X836813D03*
X833466D03*
X830120D03*
X826773D03*
X823427D03*
X820080D03*
X816734D03*
X813387D03*
X810041D03*
X806694D03*
X803348D03*
X800002D03*
X796655D03*
X793309D03*
X789962D03*
X846852Y505024D03*
X843506D03*
X840159D03*
X836813D03*
X833466D03*
X830120D03*
X826773D03*
X823427D03*
X820080D03*
X816734D03*
X813387D03*
X810041D03*
X806694D03*
X803348D03*
X800002D03*
X796655D03*
X793309D03*
X789962D03*
X846852Y523134D03*
X843506D03*
X840159D03*
X836813D03*
X833466D03*
X830120D03*
X826773D03*
X823427D03*
X820080D03*
X816734D03*
X813387D03*
X810041D03*
X806694D03*
X803348D03*
X800002D03*
X796655D03*
X793309D03*
X789962D03*
X846852Y580624D03*
X843506D03*
X840159D03*
X836813D03*
X833466D03*
X830120D03*
X826773D03*
X823427D03*
X820080D03*
X816734D03*
X813387D03*
X810041D03*
X806694D03*
X803348D03*
X800002D03*
X796655D03*
X793309D03*
X789962D03*
X846852Y542824D03*
X843506D03*
X840159D03*
X836813D03*
X833466D03*
X830120D03*
X826773D03*
X823427D03*
X820080D03*
X816734D03*
X813387D03*
X810041D03*
X806694D03*
X803348D03*
X800002D03*
X796655D03*
X793309D03*
X789962D03*
X846852Y560934D03*
X843506D03*
X840159D03*
X836813D03*
X833466D03*
X830120D03*
X826773D03*
X823427D03*
X820080D03*
X816734D03*
X813387D03*
X810041D03*
X806694D03*
X803348D03*
X800002D03*
X796655D03*
X793309D03*
X789962D03*
X846852Y598734D03*
X843506D03*
X840159D03*
X836813D03*
X833466D03*
X830120D03*
X826773D03*
X823427D03*
X820080D03*
X816734D03*
X813387D03*
X810041D03*
X806694D03*
X803348D03*
X800002D03*
X796655D03*
X793309D03*
X789962D03*
X910435Y4023D03*
X907088D03*
X903742D03*
X900395D03*
X897049D03*
X893702D03*
X890356D03*
X887009D03*
X883663D03*
X880317D03*
X876970D03*
X873624D03*
X870277D03*
X866931D03*
X863584D03*
X860238D03*
X856891D03*
X853545D03*
X850198D03*
X910435Y22133D03*
X907088D03*
X903742D03*
X900395D03*
X897049D03*
X893702D03*
X890356D03*
X887009D03*
X883663D03*
X880317D03*
X876970D03*
X873624D03*
X870277D03*
X866931D03*
X863584D03*
X860238D03*
X856891D03*
X853545D03*
X850198D03*
X910435Y79623D03*
X907088D03*
X903742D03*
X900395D03*
X897049D03*
X893702D03*
X890356D03*
X887009D03*
X883663D03*
X880317D03*
X876970D03*
X873624D03*
X870277D03*
X866931D03*
X863584D03*
X860238D03*
X856891D03*
X853545D03*
X850198D03*
X910435Y97733D03*
X907088D03*
X903742D03*
X900395D03*
X897049D03*
X893702D03*
X890356D03*
X887009D03*
X883663D03*
X880317D03*
X876970D03*
X873624D03*
X870277D03*
X866931D03*
X863584D03*
X860238D03*
X856891D03*
X853545D03*
X850198D03*
X910435Y41823D03*
X907088D03*
X903742D03*
X900395D03*
X897049D03*
X893702D03*
X890356D03*
X887009D03*
X883663D03*
X880317D03*
X876970D03*
X873624D03*
X870277D03*
X866931D03*
X863584D03*
X860238D03*
X856891D03*
X853545D03*
X850198D03*
X910435Y59933D03*
X907088D03*
X903742D03*
X900395D03*
X897049D03*
X893702D03*
X890356D03*
X887009D03*
X883663D03*
X880317D03*
X876970D03*
X873624D03*
X870277D03*
X866931D03*
X863584D03*
X860238D03*
X856891D03*
X853545D03*
X850198D03*
X910435Y505024D03*
X907088D03*
X903742D03*
X900395D03*
X897049D03*
X893702D03*
X890356D03*
X887009D03*
X883663D03*
X880317D03*
X876970D03*
X873624D03*
X870277D03*
X866931D03*
X863584D03*
X860238D03*
X856891D03*
X853545D03*
X850198D03*
X910435Y523134D03*
X907088D03*
X903742D03*
X900395D03*
X897049D03*
X893702D03*
X890356D03*
X887009D03*
X883663D03*
X880317D03*
X876970D03*
X873624D03*
X870277D03*
X866931D03*
X863584D03*
X860238D03*
X856891D03*
X853545D03*
X850198D03*
X910435Y580624D03*
X907088D03*
X903742D03*
X900395D03*
X897049D03*
X893702D03*
X890356D03*
X887009D03*
X883663D03*
X880317D03*
X876970D03*
X873624D03*
X870277D03*
X866931D03*
X863584D03*
X860238D03*
X856891D03*
X853545D03*
X850198D03*
X910435Y542824D03*
X907088D03*
X903742D03*
X900395D03*
X897049D03*
X893702D03*
X890356D03*
X887009D03*
X883663D03*
X880317D03*
X876970D03*
X873624D03*
X870277D03*
X866931D03*
X863584D03*
X860238D03*
X856891D03*
X853545D03*
X850198D03*
X910435Y560934D03*
X907088D03*
X903742D03*
X900395D03*
X897049D03*
X893702D03*
X890356D03*
X887009D03*
X883663D03*
X880317D03*
X876970D03*
X873624D03*
X870277D03*
X866931D03*
X863584D03*
X860238D03*
X856891D03*
X853545D03*
X850198D03*
X910435Y598734D03*
X907088D03*
X903742D03*
X900395D03*
X897049D03*
X893702D03*
X890356D03*
X887009D03*
X883663D03*
X880317D03*
X876970D03*
X873624D03*
X870277D03*
X866931D03*
X863584D03*
X860238D03*
X856891D03*
X853545D03*
X850198D03*
X970671Y4023D03*
X967324D03*
X963978D03*
X960631D03*
X957285D03*
X953939D03*
X950592D03*
X947246D03*
X943899D03*
X940553D03*
X937206D03*
X933860D03*
X930513D03*
X927167D03*
X923820D03*
X920474D03*
X917128D03*
X913781D03*
X970671Y22133D03*
X967324D03*
X963978D03*
X960631D03*
X957285D03*
X953939D03*
X950592D03*
X947246D03*
X943899D03*
X940553D03*
X937206D03*
X933860D03*
X930513D03*
X927167D03*
X923820D03*
X920474D03*
X917128D03*
X913781D03*
X970671Y79623D03*
X967324D03*
X963978D03*
X960631D03*
X957285D03*
X953939D03*
X950592D03*
X947246D03*
X943899D03*
X940553D03*
X937206D03*
X933860D03*
X930513D03*
X927167D03*
X923820D03*
X920474D03*
X917128D03*
X913781D03*
X970671Y97733D03*
X967324D03*
X963978D03*
X960631D03*
X957285D03*
X953939D03*
X950592D03*
X947246D03*
X943899D03*
X940553D03*
X937206D03*
X933860D03*
X930513D03*
X927167D03*
X923820D03*
X920474D03*
X917128D03*
X913781D03*
X970671Y41823D03*
X967324D03*
X963978D03*
X960631D03*
X957285D03*
X953939D03*
X950592D03*
X947246D03*
X943899D03*
X940553D03*
X937206D03*
X933860D03*
X930513D03*
X927167D03*
X923820D03*
X920474D03*
X917128D03*
X913781D03*
X970671Y59933D03*
X967324D03*
X963978D03*
X960631D03*
X957285D03*
X953939D03*
X950592D03*
X947246D03*
X943899D03*
X940553D03*
X937206D03*
X933860D03*
X930513D03*
X927167D03*
X923820D03*
X920474D03*
X917128D03*
X913781D03*
X970671Y505024D03*
X967324D03*
X963978D03*
X960631D03*
X957285D03*
X953939D03*
X950592D03*
X947246D03*
X943899D03*
X940553D03*
X937206D03*
X933860D03*
X930513D03*
X927167D03*
X923820D03*
X920474D03*
X917128D03*
X913781D03*
X970671Y523134D03*
X967324D03*
X963978D03*
X960631D03*
X957285D03*
X953939D03*
X950592D03*
X947246D03*
X943899D03*
X940553D03*
X937206D03*
X933860D03*
X930513D03*
X927167D03*
X923820D03*
X920474D03*
X917128D03*
X913781D03*
X970671Y580624D03*
X967324D03*
X963978D03*
X960631D03*
X957285D03*
X953939D03*
X950592D03*
X947246D03*
X943899D03*
X940553D03*
X937206D03*
X933860D03*
X930513D03*
X927167D03*
X923820D03*
X920474D03*
X917128D03*
X913781D03*
X970671Y542824D03*
X967324D03*
X963978D03*
X960631D03*
X957285D03*
X953939D03*
X950592D03*
X947246D03*
X943899D03*
X940553D03*
X937206D03*
X933860D03*
X930513D03*
X927167D03*
X923820D03*
X920474D03*
X917128D03*
X913781D03*
X970671Y560934D03*
X967324D03*
X963978D03*
X960631D03*
X957285D03*
X953939D03*
X950592D03*
X947246D03*
X943899D03*
X940553D03*
X937206D03*
X933860D03*
X930513D03*
X927167D03*
X923820D03*
X920474D03*
X917128D03*
X913781D03*
X970671Y598734D03*
X967324D03*
X963978D03*
X960631D03*
X957285D03*
X953939D03*
X950592D03*
X947246D03*
X943899D03*
X940553D03*
X937206D03*
X933860D03*
X930513D03*
X927167D03*
X923820D03*
X920474D03*
X917128D03*
X913781D03*
X1020868Y4023D03*
X1017521D03*
X1014175D03*
X1010828D03*
X1007482D03*
X1004135D03*
X1000789D03*
X997443D03*
X994096D03*
X990750D03*
X987403D03*
X984057D03*
X980710D03*
X977364D03*
X974017D03*
X1020868Y22133D03*
X1017521D03*
X1014175D03*
X1010828D03*
X1007482D03*
X1004135D03*
X1000789D03*
X997443D03*
X994096D03*
X990750D03*
X987403D03*
X984057D03*
X980710D03*
X977364D03*
X974017D03*
X1020868Y79623D03*
X1017521D03*
X1014175D03*
X1010828D03*
X1007482D03*
X1004135D03*
X1000789D03*
X997443D03*
X994096D03*
X990750D03*
X987403D03*
X984057D03*
X980710D03*
X977364D03*
X974017D03*
X1020868Y97733D03*
X1017521D03*
X1014175D03*
X1010828D03*
X1007482D03*
X1004135D03*
X1000789D03*
X997443D03*
X994096D03*
X990750D03*
X987403D03*
X984057D03*
X980710D03*
X977364D03*
X974017D03*
X1020868Y41823D03*
X1017521D03*
X1014175D03*
X1010828D03*
X1007482D03*
X1004135D03*
X1000789D03*
X997443D03*
X994096D03*
X990750D03*
X987403D03*
X984057D03*
X980710D03*
X977364D03*
X974017D03*
X1020868Y59933D03*
X1017521D03*
X1014175D03*
X1010828D03*
X1007482D03*
X1004135D03*
X1000789D03*
X997443D03*
X994096D03*
X990750D03*
X987403D03*
X984057D03*
X980710D03*
X977364D03*
X974017D03*
X1020868Y505024D03*
X1017521D03*
X1014175D03*
X1010828D03*
X1007482D03*
X1004135D03*
X1000789D03*
X997443D03*
X994096D03*
X990750D03*
X987403D03*
X984057D03*
X980710D03*
X977364D03*
X974017D03*
X1020868Y523134D03*
X1017521D03*
X1014175D03*
X1010828D03*
X1007482D03*
X1004135D03*
X1000789D03*
X997443D03*
X994096D03*
X990750D03*
X987403D03*
X984057D03*
X980710D03*
X977364D03*
X974017D03*
X1020868Y580624D03*
X1017521D03*
X1014175D03*
X1010828D03*
X1007482D03*
X1004135D03*
X1000789D03*
X997443D03*
X994096D03*
X990750D03*
X987403D03*
X984057D03*
X980710D03*
X977364D03*
X974017D03*
X1020868Y542824D03*
X1017521D03*
X1014175D03*
X1010828D03*
X1007482D03*
X1004135D03*
X1000789D03*
X997443D03*
X994096D03*
X990750D03*
X987403D03*
X984057D03*
X980710D03*
X977364D03*
X974017D03*
X1020868Y560934D03*
X1017521D03*
X1014175D03*
X1010828D03*
X1007482D03*
X1004135D03*
X1000789D03*
X997443D03*
X994096D03*
X990750D03*
X987403D03*
X984057D03*
X980710D03*
X977364D03*
X974017D03*
X1020868Y598734D03*
X1017521D03*
X1014175D03*
X1010828D03*
X1007482D03*
X1004135D03*
X1000789D03*
X997443D03*
X994096D03*
X990750D03*
X987403D03*
X984057D03*
X980710D03*
X977364D03*
X974017D03*
X1094490Y4023D03*
X1091143D03*
X1087797D03*
X1084450D03*
X1081104D03*
X1077757D03*
X1074411D03*
X1071065D03*
X1067718D03*
X1064372D03*
X1061025D03*
X1057679D03*
X1054332D03*
X1050986D03*
X1047639D03*
X1044293D03*
X1094490Y22133D03*
X1091143D03*
X1087797D03*
X1084450D03*
X1081104D03*
X1077757D03*
X1074411D03*
X1071065D03*
X1067718D03*
X1064372D03*
X1061025D03*
X1057679D03*
X1054332D03*
X1050986D03*
X1047639D03*
X1044293D03*
X1094490Y79623D03*
X1091143D03*
X1087797D03*
X1084450D03*
X1081104D03*
X1077757D03*
X1074411D03*
X1071065D03*
X1067718D03*
X1064372D03*
X1061025D03*
X1057679D03*
X1054332D03*
X1050986D03*
X1047639D03*
X1044293D03*
X1094490Y97733D03*
X1091143D03*
X1087797D03*
X1084450D03*
X1081104D03*
X1077757D03*
X1074411D03*
X1071065D03*
X1067718D03*
X1064372D03*
X1061025D03*
X1057679D03*
X1054332D03*
X1050986D03*
X1047639D03*
X1044293D03*
X1094490Y41823D03*
X1091143D03*
X1087797D03*
X1084450D03*
X1081104D03*
X1077757D03*
X1074411D03*
X1071065D03*
X1067718D03*
X1064372D03*
X1061025D03*
X1057679D03*
X1054332D03*
X1050986D03*
X1047639D03*
X1044293D03*
X1094490Y59933D03*
X1091143D03*
X1087797D03*
X1084450D03*
X1081104D03*
X1077757D03*
X1074411D03*
X1071065D03*
X1067718D03*
X1064372D03*
X1061025D03*
X1057679D03*
X1054332D03*
X1050986D03*
X1047639D03*
X1044293D03*
X1094490Y505024D03*
X1091143D03*
X1087797D03*
X1084450D03*
X1081104D03*
X1077757D03*
X1074411D03*
X1071065D03*
X1067718D03*
X1064372D03*
X1061025D03*
X1057679D03*
X1054332D03*
X1050986D03*
X1047639D03*
X1044293D03*
X1094490Y523134D03*
X1091143D03*
X1087797D03*
X1084450D03*
X1081104D03*
X1077757D03*
X1074411D03*
X1071065D03*
X1067718D03*
X1064372D03*
X1061025D03*
X1057679D03*
X1054332D03*
X1050986D03*
X1047639D03*
X1044293D03*
X1094490Y580624D03*
X1091143D03*
X1087797D03*
X1084450D03*
X1081104D03*
X1077757D03*
X1074411D03*
X1071065D03*
X1067718D03*
X1064372D03*
X1061025D03*
X1057679D03*
X1054332D03*
X1050986D03*
X1047639D03*
X1044293D03*
X1094490Y542824D03*
X1091143D03*
X1087797D03*
X1084450D03*
X1081104D03*
X1077757D03*
X1074411D03*
X1071065D03*
X1067718D03*
X1064372D03*
X1061025D03*
X1057679D03*
X1054332D03*
X1050986D03*
X1047639D03*
X1044293D03*
X1094490Y560934D03*
X1091143D03*
X1087797D03*
X1084450D03*
X1081104D03*
X1077757D03*
X1074411D03*
X1071065D03*
X1067718D03*
X1064372D03*
X1061025D03*
X1057679D03*
X1054332D03*
X1050986D03*
X1047639D03*
X1044293D03*
X1094490Y598734D03*
X1091143D03*
X1087797D03*
X1084450D03*
X1081104D03*
X1077757D03*
X1074411D03*
X1071065D03*
X1067718D03*
X1064372D03*
X1061025D03*
X1057679D03*
X1054332D03*
X1050986D03*
X1047639D03*
X1044293D03*
X1154726Y4023D03*
X1151380D03*
X1148033D03*
X1144687D03*
X1141340D03*
X1137994D03*
X1134647D03*
X1131301D03*
X1127954D03*
X1124608D03*
X1121261D03*
X1117915D03*
X1114568D03*
X1111222D03*
X1107876D03*
X1104529D03*
X1101183D03*
X1097836D03*
X1154726Y22133D03*
X1151380D03*
X1148033D03*
X1144687D03*
X1141340D03*
X1137994D03*
X1134647D03*
X1131301D03*
X1127954D03*
X1124608D03*
X1121261D03*
X1117915D03*
X1114568D03*
X1111222D03*
X1107876D03*
X1104529D03*
X1101183D03*
X1097836D03*
X1154726Y79623D03*
X1151380D03*
X1148033D03*
X1144687D03*
X1141340D03*
X1137994D03*
X1134647D03*
X1131301D03*
X1127954D03*
X1124608D03*
X1121261D03*
X1117915D03*
X1114568D03*
X1111222D03*
X1107876D03*
X1104529D03*
X1101183D03*
X1097836D03*
X1154726Y97733D03*
X1151380D03*
X1148033D03*
X1144687D03*
X1141340D03*
X1137994D03*
X1134647D03*
X1131301D03*
X1127954D03*
X1124608D03*
X1121261D03*
X1117915D03*
X1114568D03*
X1111222D03*
X1107876D03*
X1104529D03*
X1101183D03*
X1097836D03*
X1154726Y41823D03*
X1151380D03*
X1148033D03*
X1144687D03*
X1141340D03*
X1137994D03*
X1134647D03*
X1131301D03*
X1127954D03*
X1124608D03*
X1121261D03*
X1117915D03*
X1114568D03*
X1111222D03*
X1107876D03*
X1104529D03*
X1101183D03*
X1097836D03*
X1154726Y59933D03*
X1151380D03*
X1148033D03*
X1144687D03*
X1141340D03*
X1137994D03*
X1134647D03*
X1131301D03*
X1127954D03*
X1124608D03*
X1121261D03*
X1117915D03*
X1114568D03*
X1111222D03*
X1107876D03*
X1104529D03*
X1101183D03*
X1097836D03*
X1154726Y505024D03*
X1151380D03*
X1148033D03*
X1144687D03*
X1141340D03*
X1137994D03*
X1134647D03*
X1131301D03*
X1127954D03*
X1124608D03*
X1121261D03*
X1117915D03*
X1114568D03*
X1111222D03*
X1107876D03*
X1104529D03*
X1101183D03*
X1097836D03*
X1154726Y523134D03*
X1151380D03*
X1148033D03*
X1144687D03*
X1141340D03*
X1137994D03*
X1134647D03*
X1131301D03*
X1127954D03*
X1124608D03*
X1121261D03*
X1117915D03*
X1114568D03*
X1111222D03*
X1107876D03*
X1104529D03*
X1101183D03*
X1097836D03*
X1154726Y580624D03*
X1151380D03*
X1148033D03*
X1144687D03*
X1141340D03*
X1137994D03*
X1134647D03*
X1131301D03*
X1127954D03*
X1124608D03*
X1121261D03*
X1117915D03*
X1114568D03*
X1111222D03*
X1107876D03*
X1104529D03*
X1101183D03*
X1097836D03*
X1154726Y542824D03*
X1151380D03*
X1148033D03*
X1144687D03*
X1141340D03*
X1137994D03*
X1134647D03*
X1131301D03*
X1127954D03*
X1124608D03*
X1121261D03*
X1117915D03*
X1114568D03*
X1111222D03*
X1107876D03*
X1104529D03*
X1101183D03*
X1097836D03*
X1154726Y560934D03*
X1151380D03*
X1148033D03*
X1144687D03*
X1141340D03*
X1137994D03*
X1134647D03*
X1131301D03*
X1127954D03*
X1124608D03*
X1121261D03*
X1117915D03*
X1114568D03*
X1111222D03*
X1107876D03*
X1104529D03*
X1101183D03*
X1097836D03*
X1154726Y598734D03*
X1151380D03*
X1148033D03*
X1144687D03*
X1141340D03*
X1137994D03*
X1134647D03*
X1131301D03*
X1127954D03*
X1124608D03*
X1121261D03*
X1117915D03*
X1114568D03*
X1111222D03*
X1107876D03*
X1104529D03*
X1101183D03*
X1097836D03*
X1218309Y4023D03*
X1214962D03*
X1211616D03*
X1208269D03*
X1204923D03*
X1201576D03*
X1198230D03*
X1194883D03*
X1191537D03*
X1188191D03*
X1184844D03*
X1181498D03*
X1178151D03*
X1174805D03*
X1171458D03*
X1168112D03*
X1164765D03*
X1161419D03*
X1158072D03*
X1218309Y22133D03*
X1214962D03*
X1211616D03*
X1208269D03*
X1204923D03*
X1201576D03*
X1198230D03*
X1194883D03*
X1191537D03*
X1188191D03*
X1184844D03*
X1181498D03*
X1178151D03*
X1174805D03*
X1171458D03*
X1168112D03*
X1164765D03*
X1161419D03*
X1158072D03*
X1218309Y79623D03*
X1214962D03*
X1211616D03*
X1208269D03*
X1204923D03*
X1201576D03*
X1198230D03*
X1194883D03*
X1191537D03*
X1188191D03*
X1184844D03*
X1181498D03*
X1178151D03*
X1174805D03*
X1171458D03*
X1168112D03*
X1164765D03*
X1161419D03*
X1158072D03*
X1218309Y97733D03*
X1214962D03*
X1211616D03*
X1208269D03*
X1204923D03*
X1201576D03*
X1198230D03*
X1194883D03*
X1191537D03*
X1188191D03*
X1184844D03*
X1181498D03*
X1178151D03*
X1174805D03*
X1171458D03*
X1168112D03*
X1164765D03*
X1161419D03*
X1158072D03*
X1218309Y41823D03*
X1214962D03*
X1211616D03*
X1208269D03*
X1204923D03*
X1201576D03*
X1198230D03*
X1194883D03*
X1191537D03*
X1188191D03*
X1184844D03*
X1181498D03*
X1178151D03*
X1174805D03*
X1171458D03*
X1168112D03*
X1164765D03*
X1161419D03*
X1158072D03*
X1218309Y59933D03*
X1214962D03*
X1211616D03*
X1208269D03*
X1204923D03*
X1201576D03*
X1198230D03*
X1194883D03*
X1191537D03*
X1188191D03*
X1184844D03*
X1181498D03*
X1178151D03*
X1174805D03*
X1171458D03*
X1168112D03*
X1164765D03*
X1161419D03*
X1158072D03*
X1218309Y505024D03*
X1214962D03*
X1211616D03*
X1208269D03*
X1204923D03*
X1201576D03*
X1198230D03*
X1194883D03*
X1191537D03*
X1188191D03*
X1184844D03*
X1181498D03*
X1178151D03*
X1174805D03*
X1171458D03*
X1168112D03*
X1164765D03*
X1161419D03*
X1158072D03*
X1218309Y523134D03*
X1214962D03*
X1211616D03*
X1208269D03*
X1204923D03*
X1201576D03*
X1198230D03*
X1194883D03*
X1191537D03*
X1188191D03*
X1184844D03*
X1181498D03*
X1178151D03*
X1174805D03*
X1171458D03*
X1168112D03*
X1164765D03*
X1161419D03*
X1158072D03*
X1218309Y580624D03*
X1214962D03*
X1211616D03*
X1208269D03*
X1204923D03*
X1201576D03*
X1198230D03*
X1194883D03*
X1191537D03*
X1188191D03*
X1184844D03*
X1181498D03*
X1178151D03*
X1174805D03*
X1171458D03*
X1168112D03*
X1164765D03*
X1161419D03*
X1158072D03*
X1218309Y542824D03*
X1214962D03*
X1211616D03*
X1208269D03*
X1204923D03*
X1201576D03*
X1198230D03*
X1194883D03*
X1191537D03*
X1188191D03*
X1184844D03*
X1181498D03*
X1178151D03*
X1174805D03*
X1171458D03*
X1168112D03*
X1164765D03*
X1161419D03*
X1158072D03*
X1218309Y560934D03*
X1214962D03*
X1211616D03*
X1208269D03*
X1204923D03*
X1201576D03*
X1198230D03*
X1194883D03*
X1191537D03*
X1188191D03*
X1184844D03*
X1181498D03*
X1178151D03*
X1174805D03*
X1171458D03*
X1168112D03*
X1164765D03*
X1161419D03*
X1158072D03*
X1218309Y598734D03*
X1214962D03*
X1211616D03*
X1208269D03*
X1204923D03*
X1201576D03*
X1198230D03*
X1194883D03*
X1191537D03*
X1188191D03*
X1184844D03*
X1181498D03*
X1178151D03*
X1174805D03*
X1171458D03*
X1168112D03*
X1164765D03*
X1161419D03*
X1158072D03*
X1265159Y4023D03*
X1261813D03*
X1258466D03*
X1255120D03*
X1251773D03*
X1248427D03*
X1245080D03*
X1241734D03*
X1238387D03*
X1235041D03*
X1231694D03*
X1228348D03*
X1225002D03*
X1221655D03*
X1265159Y22133D03*
X1261813D03*
X1258466D03*
X1255120D03*
X1251773D03*
X1248427D03*
X1245080D03*
X1241734D03*
X1238387D03*
X1235041D03*
X1231694D03*
X1228348D03*
X1225002D03*
X1221655D03*
X1265159Y79623D03*
X1261813D03*
X1258466D03*
X1255120D03*
X1251773D03*
X1248427D03*
X1245080D03*
X1241734D03*
X1238387D03*
X1235041D03*
X1231694D03*
X1228348D03*
X1225002D03*
X1221655D03*
X1265159Y97733D03*
X1261813D03*
X1258466D03*
X1255120D03*
X1251773D03*
X1248427D03*
X1245080D03*
X1241734D03*
X1238387D03*
X1235041D03*
X1231694D03*
X1228348D03*
X1225002D03*
X1221655D03*
X1265159Y41823D03*
X1261813D03*
X1258466D03*
X1255120D03*
X1251773D03*
X1248427D03*
X1245080D03*
X1241734D03*
X1238387D03*
X1235041D03*
X1231694D03*
X1228348D03*
X1225002D03*
X1221655D03*
X1265159Y59933D03*
X1261813D03*
X1258466D03*
X1255120D03*
X1251773D03*
X1248427D03*
X1245080D03*
X1241734D03*
X1238387D03*
X1235041D03*
X1231694D03*
X1228348D03*
X1225002D03*
X1221655D03*
X1265159Y505024D03*
X1261813D03*
X1258466D03*
X1255120D03*
X1251773D03*
X1248427D03*
X1245080D03*
X1241734D03*
X1238387D03*
X1235041D03*
X1231694D03*
X1228348D03*
X1225002D03*
X1221655D03*
X1265159Y523134D03*
X1261813D03*
X1258466D03*
X1255120D03*
X1251773D03*
X1248427D03*
X1245080D03*
X1241734D03*
X1238387D03*
X1235041D03*
X1231694D03*
X1228348D03*
X1225002D03*
X1221655D03*
X1265159Y580624D03*
X1261813D03*
X1258466D03*
X1255120D03*
X1251773D03*
X1248427D03*
X1245080D03*
X1241734D03*
X1238387D03*
X1235041D03*
X1231694D03*
X1228348D03*
X1225002D03*
X1221655D03*
X1265159Y542824D03*
X1261813D03*
X1258466D03*
X1255120D03*
X1251773D03*
X1248427D03*
X1245080D03*
X1241734D03*
X1238387D03*
X1235041D03*
X1231694D03*
X1228348D03*
X1225002D03*
X1221655D03*
X1265159Y560934D03*
X1261813D03*
X1258466D03*
X1255120D03*
X1251773D03*
X1248427D03*
X1245080D03*
X1241734D03*
X1238387D03*
X1235041D03*
X1231694D03*
X1228348D03*
X1225002D03*
X1221655D03*
X1265159Y598734D03*
X1261813D03*
X1258466D03*
X1255120D03*
X1251773D03*
X1248427D03*
X1245080D03*
X1241734D03*
X1238387D03*
X1235041D03*
X1231694D03*
X1228348D03*
X1225002D03*
X1221655D03*
G54D193*
X1807521Y587899D03*
X1813505D03*
G54D28*
X20340Y24559D03*
X16720Y53240D03*
X6840Y564000D03*
X8530Y529080D03*
X130564Y209283D03*
X130774Y241333D03*
X130250Y273300D03*
X130574Y305323D03*
Y337533D03*
X130834Y369363D03*
X780152Y209163D03*
X780182Y241283D03*
Y273533D03*
X780892Y305563D03*
X780722Y337353D03*
X780112Y369433D03*
G36*
G01X24103Y622608D02*
G02Y598654I-10303J-11977D01*
G02X3767Y598425I-10304J11976D01*
G03X2702Y598731I-1068J-1710D01*
G01X-3D01*
G02X-11901Y610631I2J11900D01*
G02X-1Y622531I11901J-1D01*
G01X2709D01*
G03X3764Y622834I-1J1990D01*
G02X24103Y622608I10035J-12202D01*
G37*
G36*
G01X701268Y4104D02*
G02Y-19850I-10303J-11977D01*
G02X680932Y-20079I-10304J11976D01*
G03X679867Y-19773I-1068J-1710D01*
G01X677162D01*
G02X665264Y-7873I2J11900D01*
G02X677164Y4027I11901J-1D01*
G01X679874D01*
G03X680929Y4330I-1J1990D01*
G02X701268Y4104I10035J-12202D01*
G37*
G36*
G01Y622608D02*
G02Y598654I-10303J-11977D01*
G02X680932Y598425I-10304J11976D01*
G03X679867Y598731I-1068J-1710D01*
G01X677162D01*
G02X665264Y610631I2J11900D01*
G02X677164Y622531I11901J-1D01*
G01X679874D01*
G03X680929Y622834I-1J1990D01*
G02X701268Y622608I10035J-12202D01*
G37*
G36*
G01X1429615Y4104D02*
G02Y-19850I-10303J-11977D01*
G02X1409279Y-20079I-10304J11976D01*
G03X1408214Y-19773I-1068J-1710D01*
G01X1405509D01*
G02X1393611Y-7873I2J11900D01*
G02X1405511Y4027I11901J-1D01*
G01X1408221D01*
G03X1409276Y4330I-1J1990D01*
G02X1429615Y4104I10035J-12202D01*
G37*
G36*
G01Y622608D02*
G02Y598654I-10303J-11977D01*
G02X1409279Y598425I-10304J11976D01*
G03X1408214Y598731I-1068J-1710D01*
G01X1405509D01*
G02X1393611Y610631I2J11900D01*
G02X1405511Y622531I11901J-1D01*
G01X1408221D01*
G03X1409276Y622834I-1J1990D01*
G02X1429615Y622608I10035J-12202D01*
G37*
G36*
G01X1878434Y4104D02*
G02Y-19850I-10303J-11977D01*
G02X1858098Y-20079I-10304J11976D01*
G03X1857033Y-19773I-1068J-1710D01*
G01X1854328D01*
G02X1842430Y-7873I2J11900D01*
G02X1854330Y4027I11901J-1D01*
G01X1857040D01*
G03X1858095Y4330I-1J1990D01*
G02X1878434Y4104I10035J-12202D01*
G37*
G36*
G01Y622608D02*
G02Y598654I-10303J-11977D01*
G02X1858098Y598425I-10304J11976D01*
G03X1857033Y598731I-1068J-1710D01*
G01X1854328D01*
G02X1842430Y610631I2J11900D01*
G02X1854330Y622531I11901J-1D01*
G01X1857040D01*
G03X1858095Y622834I-1J1990D01*
G02X1878434Y622608I10035J-12202D01*
G37*
G54D19*
X-13780Y598560D03*
X-3937Y-43307D03*
Y646063D03*
X1956693Y-43307D03*
Y646063D03*
G54D37*
X40512Y458744D03*
G54D166*
X1629039Y580079D03*
X1626087Y585591D03*
X1629039Y565118D03*
X1626087Y570630D03*
X1637898Y580079D03*
X1634945Y585591D03*
X1637898Y565118D03*
X1634945Y570630D03*
X1643803D03*
X1646756Y565118D03*
Y580079D03*
X1643803Y585591D03*
X1640850Y582835D03*
X1631992D03*
X1623134D03*
X1640850Y567874D03*
X1631992D03*
X1623134D03*
X1646756Y610000D03*
Y595039D03*
X1643803Y600551D03*
Y615512D03*
X1629039Y610000D03*
X1626087Y615512D03*
X1629039Y595039D03*
X1626087Y600551D03*
X1637898Y610000D03*
X1634945Y615512D03*
X1637898Y595039D03*
X1634945Y600551D03*
X1623134Y612756D03*
X1640850Y597795D03*
X1631992D03*
X1623134D03*
X1640850Y612756D03*
X1631992D03*
X1676283Y580079D03*
X1673331Y585591D03*
X1676283Y565118D03*
X1673331Y570630D03*
X1685142Y580079D03*
X1682189Y585591D03*
X1685142Y565118D03*
X1682189Y570630D03*
X1691047D03*
X1694000Y565118D03*
Y580079D03*
X1691047Y585591D03*
X1688094Y582835D03*
X1679236D03*
X1670378D03*
X1688094Y567874D03*
X1679236D03*
X1670378D03*
X1694000Y595039D03*
X1691047Y600551D03*
Y615512D03*
X1676283Y610000D03*
X1673331Y615512D03*
X1676283Y595039D03*
X1673331Y600551D03*
X1685142Y610000D03*
X1682189Y615512D03*
X1685142Y595039D03*
X1682189Y600551D03*
X1688094Y612756D03*
X1679236D03*
X1670378D03*
X1688094Y597795D03*
X1679236D03*
X1670378D03*
G54D157*
X1629849Y156438D03*
X1685800Y165650D03*
X1785703Y69879D03*
X1839250Y98250D03*
G54D83*
X543984Y131273D03*
G54D185*
X1750315Y560887D03*
Y566793D03*
X1803950Y538954D03*
Y533048D03*
G54D194*
X1804450Y597938D03*
Y594001D03*
Y595970D03*
Y592032D03*
Y590064D03*
G54D29*
X46777Y-16430D03*
Y-8830D03*
X35677Y-16430D03*
Y-8830D03*
X706270Y243945D03*
Y236345D03*
X714900Y244090D03*
Y236490D03*
X723604Y237024D03*
Y229424D03*
X736500Y208700D03*
Y216300D03*
X732344Y237043D03*
Y229443D03*
X741055Y241836D03*
Y234236D03*
X1380000Y414300D03*
Y406700D03*
X1372000Y414300D03*
Y406700D03*
X1364000Y414300D03*
Y406700D03*
X1388000Y414300D03*
Y406700D03*
X1356655Y523455D03*
Y531055D03*
X1398950Y574260D03*
Y581860D03*
X1429261Y568923D03*
Y576523D03*
X1437013Y568923D03*
Y576523D03*
X1409404Y574063D03*
Y581663D03*
X1448526Y593422D03*
Y601022D03*
X1456694Y618570D03*
Y610970D03*
X1448694Y618570D03*
Y610970D03*
X1440694Y618570D03*
Y610970D03*
X1922224Y216107D03*
X1914569Y216096D03*
X1922224Y223707D03*
X1914569Y223696D03*
X1968487Y214193D03*
Y221793D03*
G54D47*
X94683Y-5822D03*
Y31978D03*
Y13078D03*
Y69778D03*
Y50878D03*
Y88678D03*
Y514079D03*
Y532955D03*
Y570755D03*
Y589679D03*
Y551879D03*
Y608555D03*
X637793Y-5822D03*
Y31978D03*
Y13078D03*
Y69778D03*
Y50878D03*
Y88678D03*
Y514079D03*
Y532955D03*
Y570755D03*
Y589679D03*
Y551879D03*
Y608555D03*
X744293Y-5822D03*
Y31978D03*
Y13078D03*
Y69778D03*
Y88678D03*
Y50878D03*
Y514079D03*
Y570755D03*
Y532955D03*
Y589679D03*
Y551879D03*
Y608555D03*
X1287403Y-5822D03*
Y31978D03*
Y13078D03*
Y69778D03*
Y88678D03*
Y50878D03*
Y514079D03*
Y570755D03*
Y532955D03*
Y589679D03*
Y551879D03*
Y608555D03*
G54D74*
X177070Y121250D03*
X237330Y408960D03*
X475000Y122500D03*
X539500Y478000D03*
X735000Y392500D03*
X872000Y111000D03*
X1215624Y133363D03*
X1225000Y487600D03*
X1925000Y62000D03*
G54D149*
X1554960Y145900D03*
Y153300D03*
X1557520Y145900D03*
Y153300D03*
X1552400Y145900D03*
Y153300D03*
X1847000Y516600D03*
Y525600D03*
X1853900Y516600D03*
Y525600D03*
G54D158*
X1629618Y122418D03*
X1772903Y112612D03*
G54D65*
X80539Y320948D03*
X65800Y364500D03*
X110758Y122310D03*
X1609800Y82000D03*
X1741100Y61300D03*
X1773350Y567650D03*
Y571695D03*
X1883066Y473995D03*
G54D167*
X1667012Y-14488D03*
G54D92*
X600568Y359708D03*
G54D38*
X-4488Y425472D03*
X99980Y136909D03*
G54D176*
X1712205Y536791D03*
X1707205D03*
X1702205D03*
X1697205D03*
X1692205D03*
X1687205D03*
X1712205D03*
X1707205D03*
X1702205D03*
X1697205D03*
X1692205D03*
X1687205D03*
X1717205D03*
D03*
G54D56*
X68000Y232300D03*
G54D186*
X1752480Y557738D03*
X1754448D03*
X1756417D03*
X1758386D03*
X1760354D03*
X1806115Y529899D03*
X1810052D03*
X1808083D03*
X1812021D03*
X1813989D03*
G54D168*
X1706065Y141740D03*
X1707042Y147319D03*
G54D195*
X1816654Y594001D03*
Y590064D03*
Y592032D03*
Y595970D03*
Y597938D03*
G54D84*
X601995Y156616D03*
G54D75*
X224410Y301378D03*
X326772Y163582D03*
Y439173D03*
X500000Y163582D03*
Y439173D03*
X602362Y214764D03*
Y387992D03*
X874016Y301378D03*
X976378Y163582D03*
Y439173D03*
X1149606Y163582D03*
Y439173D03*
X1251969Y214764D03*
Y387992D03*
G54D177*
X1660158Y539547D03*
X1788110D03*
G54D159*
X1629618Y128018D03*
X1772903Y118212D03*
G54D48*
X72600Y-10500D03*
Y17500D03*
X73350Y518400D03*
Y490400D03*
X153666Y140388D03*
Y168388D03*
X705900Y347800D03*
Y375800D03*
X1317000Y70500D03*
Y42500D03*
X1296100Y136950D03*
Y108950D03*
X1316000Y209000D03*
Y181000D03*
X1407000Y105000D03*
Y133000D03*
X1422000Y63500D03*
Y91500D03*
X1440500Y63500D03*
Y91500D03*
X1451600Y583300D03*
Y555300D03*
X1475500Y581500D03*
Y553500D03*
X1496000Y581500D03*
Y553500D03*
X1519000Y581500D03*
Y553500D03*
X1559330Y577970D03*
Y549970D03*
X1540110Y577870D03*
Y549870D03*
G54D66*
X83939Y320948D03*
X69200Y364500D03*
X114158Y122310D03*
X1613200Y82000D03*
X1744500Y61300D03*
X1776750Y567650D03*
Y571695D03*
X1886466Y473995D03*
G54D39*
X17300Y455330D03*
X1839390Y64536D03*
G54D93*
X541260Y429470D03*
X540310Y443259D03*
G54D57*
X67500Y276800D03*
X84522Y389977D03*
X90811Y444806D03*
X100287Y426488D03*
X97916Y436463D03*
X82464Y407622D03*
X81387Y434036D03*
X103799Y431342D03*
X91900Y429101D03*
X599199Y240594D03*
X1077942Y112727D03*
X1371834Y263088D03*
X1366331Y258929D03*
X1378550Y344550D03*
X1450413Y246661D03*
X1476265Y437109D03*
X1565671Y534929D03*
X1576454Y547056D03*
X1624547Y123148D03*
X1624064Y174709D03*
G54D169*
X1697694Y151292D03*
X1690970Y103101D03*
X1676372Y138275D03*
X1692944Y144363D03*
X1691596Y162922D03*
G54D196*
X1813505Y600103D03*
X1807599D03*
G54D76*
X210427Y649705D03*
X398011Y649585D03*
X585478Y649314D03*
X901122Y649294D03*
X1214648Y649283D03*
X1528146Y649313D03*
G54D85*
X601747Y170876D03*
G54D94*
X632584Y147965D03*
X671037Y176163D03*
G54D58*
X61200Y274300D03*
X1339862Y256652D03*
X1397910Y248590D03*
X1389637Y258137D03*
X1346683Y251175D03*
X1353668Y255112D03*
X1368828Y247672D03*
X1382472Y256172D03*
X1346640Y260796D03*
X1362848Y252308D03*
X1387012Y250288D03*
X1528368Y508532D03*
X1583861Y67690D03*
X1597307Y114193D03*
X1750253Y135786D03*
X1716228Y154772D03*
X1931994Y212699D03*
X1928449Y226251D03*
G54D187*
X1762519Y560809D03*
Y566793D03*
X1816154Y532970D03*
Y538954D03*
G54D49*
X107249Y105000D03*
X102328D03*
X97406D03*
X92485D03*
X87564D03*
X82643D03*
X77721D03*
G54D178*
X1694000Y610000D03*
G54D67*
X94000Y310400D03*
X882380Y355289D03*
X1319247Y266720D03*
X1324460Y260962D03*
X1329815Y255507D03*
X1318297Y255241D03*
X1323510Y272768D03*
X1328865Y266711D03*
X1470500Y163700D03*
X1476800Y234017D03*
X1484890Y268660D03*
X1478400Y267500D03*
X1500000Y353010D03*
X1528400Y502500D03*
X1590293Y51938D03*
X1626600Y356893D03*
X1729189Y150153D03*
X1740889Y151176D03*
X1751189Y123542D03*
X1936170Y233087D03*
X1935220Y226688D03*
X1959200Y574929D03*
G54D77*
X317942Y32100D03*
X312442D03*
X330142D03*
X324642D03*
X343142D03*
X337642D03*
X348000D03*
X353500D03*
X317942Y69900D03*
X312442D03*
X330142D03*
X324642D03*
X343142D03*
X337642D03*
X348000D03*
X353500D03*
X307492Y109500D03*
X312992D03*
X323292Y107100D03*
X317792D03*
X307692Y495600D03*
X313192D03*
X323670Y494675D03*
X318170D03*
X317942Y533100D03*
X312442D03*
X330142D03*
X324642D03*
X343142D03*
X337642D03*
X348000D03*
X353500D03*
X317942Y570900D03*
X312442D03*
X330142D03*
X324642D03*
X343142D03*
X337642D03*
X348000D03*
X353500D03*
X362392Y31800D03*
X367892D03*
X390900Y-15300D03*
X396400D03*
X399200Y32100D03*
X404700D03*
X411650D03*
X417150D03*
X361592Y69400D03*
X367092D03*
X399200Y69900D03*
X404700D03*
X411650D03*
X417150D03*
X383580Y497770D03*
X378080D03*
X360962Y532800D03*
X366462D03*
X401950Y533100D03*
X396450D03*
X360982Y570460D03*
X366482D03*
X411650Y533100D03*
X417150D03*
X399200Y570900D03*
X404700D03*
X411650D03*
X417150D03*
X424650Y32100D03*
X430150D03*
X437008D03*
X442508D03*
X424650Y69900D03*
X430150D03*
X437008D03*
X442508D03*
X445550Y113710D03*
X440050D03*
X452120Y490771D03*
X446620D03*
X424650Y533100D03*
X430150D03*
X438508D03*
X444008D03*
X424650Y570900D03*
X430150D03*
X437008D03*
X442508D03*
X967550Y32100D03*
X962050D03*
X967550Y69900D03*
X962050D03*
X972900Y107100D03*
X967400D03*
X957100Y109500D03*
X962600D03*
X957300Y494315D03*
X962800D03*
X967778D03*
X967550Y533100D03*
X962050D03*
X967550Y570900D03*
X962050D03*
X1012000Y31800D03*
X1017500D03*
X979750Y32100D03*
X974250D03*
X992750D03*
X987250D03*
X997608D03*
X1003108D03*
X1012000Y69400D03*
X1017500D03*
X979750Y69900D03*
X974250D03*
X992750D03*
X987250D03*
X997608D03*
X1003108D03*
X1020800Y104233D03*
X1026300D03*
X1017800Y496600D03*
X1023300D03*
X973278Y494315D03*
X1011500Y532800D03*
X1017000D03*
X1011050Y570400D03*
X1016550D03*
X979750Y533100D03*
X974250D03*
X992750D03*
X987250D03*
X997608D03*
X1003108D03*
X979750Y570900D03*
X974250D03*
X992750D03*
X987250D03*
X997608D03*
X1003108D03*
X1048808Y32100D03*
X1054308D03*
X1061258D03*
X1066758D03*
X1074258D03*
X1079758D03*
X1086616D03*
X1092116D03*
X1048808Y69900D03*
X1054308D03*
X1061258D03*
X1066758D03*
X1074258D03*
X1079758D03*
X1086616D03*
X1092116D03*
X1094900Y111400D03*
X1089400D03*
X1095788Y494860D03*
X1090288D03*
X1051558Y533100D03*
X1046058D03*
X1061258D03*
X1066758D03*
X1074258D03*
X1079758D03*
X1048808Y570900D03*
X1054308D03*
X1061258D03*
X1066758D03*
X1074258D03*
X1079758D03*
X1086616D03*
X1092116D03*
X1088116Y533100D03*
X1093616D03*
X1319119Y155667D03*
X1313619D03*
X1319119Y150629D03*
X1313619D03*
G54D179*
X1756750Y81060D03*
Y75940D03*
X1763250Y78500D03*
Y75940D03*
Y81060D03*
G54D188*
X1760354Y569942D03*
X1758386D03*
X1756417D03*
X1754448D03*
X1752480D03*
X1810052Y542103D03*
X1813989D03*
X1812021D03*
X1808083D03*
X1806115D03*
G54D95*
X622421Y126575D03*
G54D59*
X94500Y299000D03*
X89000D03*
X353500Y13200D03*
X348000D03*
X324642D03*
X330142D03*
X312342D03*
X317842D03*
X337642D03*
X343142D03*
X353500Y51000D03*
X348000D03*
X312342D03*
X317842D03*
X324642D03*
X330142D03*
X337642D03*
X343142D03*
X353500Y552000D03*
X348000D03*
X312342D03*
X317842D03*
X324642D03*
X330142D03*
X337642D03*
X343142D03*
X353500Y589800D03*
X348000D03*
X312342D03*
X317842D03*
X324642D03*
X330142D03*
X337642D03*
X343142D03*
X417150Y13200D03*
X411650D03*
X361042Y13078D03*
X366542D03*
X404700Y13200D03*
X399200D03*
X417150Y51000D03*
X411650D03*
X361058Y50742D03*
X366558D03*
X404700Y51000D03*
X399200D03*
X417150Y552000D03*
X411650D03*
X360870Y551820D03*
X366370D03*
X404700Y552000D03*
X399200D03*
X417150Y589800D03*
X411650D03*
X360090Y589680D03*
X365590D03*
X404700Y589800D03*
X399200D03*
X430150Y13200D03*
X424650D03*
X442508D03*
X437008D03*
X442508Y51000D03*
X437008D03*
X430150D03*
X424650D03*
X430150Y552000D03*
X424650D03*
X442508D03*
X437008D03*
X430150Y589800D03*
X424650D03*
X442508D03*
X437008D03*
X600000Y-6700D03*
X599000Y32000D03*
Y70000D03*
X600892Y532978D03*
Y570778D03*
X599992Y609378D03*
X616500Y32000D03*
X611000D03*
X616500Y-6700D03*
X611000D03*
X605500D03*
X604500Y32000D03*
X616500Y70000D03*
X611000D03*
X604500D03*
X616892Y570778D03*
X611392D03*
X616892Y532978D03*
X611392D03*
X606392D03*
Y570778D03*
X615992Y609378D03*
X610492D03*
X605492D03*
X671000Y13600D03*
X665500D03*
X677550Y21856D03*
X683050D03*
X671000Y18500D03*
X665500D03*
X670569Y577612D03*
X665069D03*
X961950Y13200D03*
X967450D03*
X961850Y51000D03*
X967350D03*
X961950Y552000D03*
X967450D03*
X961950Y589800D03*
X967450D03*
X1010900Y13078D03*
X1016400D03*
X1003108Y13200D03*
X997608D03*
X987250D03*
X992750D03*
X974250D03*
X979750D03*
X1003108Y51000D03*
X997608D03*
X1010800Y50500D03*
X1016300D03*
X974250Y51000D03*
X979750D03*
X987250D03*
X992750D03*
X1003108Y552000D03*
X997608D03*
X1011100Y551900D03*
X1016600D03*
X974250Y552000D03*
X979750D03*
X987250D03*
X992750D03*
X1009800Y589700D03*
X1015300D03*
X974250Y589800D03*
X979750D03*
X987250D03*
X992750D03*
X1003108D03*
X997608D03*
X1092116Y13200D03*
X1086616D03*
X1079758D03*
X1074258D03*
X1066758D03*
X1061258D03*
X1054308D03*
X1048808D03*
X1092116Y51000D03*
X1086616D03*
X1079758D03*
X1074258D03*
X1066758D03*
X1061258D03*
X1054308D03*
X1048808D03*
X1092116Y552000D03*
X1086616D03*
X1079758D03*
X1074258D03*
X1066758D03*
X1061258D03*
X1054308D03*
X1048808D03*
X1079758Y589800D03*
X1074258D03*
X1092116D03*
X1086616D03*
X1066758D03*
X1061258D03*
X1054308D03*
X1048808D03*
X1249608Y-6700D03*
X1255108D03*
X1266108D03*
X1260608D03*
X1248608Y32000D03*
X1254108D03*
X1266108D03*
X1260608D03*
X1248608Y70000D03*
X1254108D03*
X1266108D03*
X1260608D03*
X1248608Y533000D03*
X1254108D03*
X1266108D03*
X1260608D03*
X1248608Y571000D03*
X1254108D03*
X1266108D03*
X1260608D03*
X1248374Y609456D03*
X1253874D03*
X1266500Y609500D03*
X1261000D03*
X1337500Y47000D03*
X1332000D03*
X1444047Y402285D03*
X1449547D03*
X1462850Y407900D03*
X1457350D03*
X1462850Y412900D03*
X1457350D03*
X1447000Y408000D03*
X1452500D03*
X1447000Y413000D03*
X1452500D03*
X1462800Y526800D03*
X1460750Y543500D03*
X1466250D03*
X1468300Y526800D03*
X1483200Y527200D03*
X1488700D03*
X1482700Y542700D03*
X1488200D03*
X1553300Y614500D03*
X1547800D03*
X1592250Y90500D03*
X1597750D03*
X1608349Y90538D03*
X1613849D03*
X1599193Y70229D03*
X1604193D03*
X1641099Y156438D03*
X1635599D03*
X1644750Y122000D03*
X1639250D03*
X1606250Y102500D03*
X1611750D03*
X1598500Y124750D03*
X1604000D03*
X1639171Y134592D03*
X1644671D03*
X1606500Y371948D03*
X1601000D03*
X1606500Y367248D03*
X1601000D03*
X1616300Y486700D03*
X1610800D03*
X1623750Y514200D03*
X1618250D03*
X1623750Y509500D03*
X1618250D03*
X1797650Y163440D03*
X1803150D03*
X1881150Y142800D03*
X1875650D03*
X1881150Y147800D03*
X1875650D03*
X1884689Y137717D03*
X1890189D03*
X1838363Y143448D03*
X1843863D03*
X1890750Y183300D03*
X1896250D03*
X1894900Y163500D03*
X1889400D03*
X1896150Y178600D03*
X1890650D03*
X1916513Y179468D03*
X1922013D03*
X1916513Y184468D03*
X1922013D03*
X1916513Y189468D03*
X1922013D03*
X1917100Y167400D03*
X1922600D03*
G54D68*
X64500Y355700D03*
X68000D03*
X667500Y254200D03*
X1504631Y601856D03*
X1466610Y604329D03*
G54D86*
X580659Y334764D03*
G54D197*
X1895945Y-2322D03*
Y5670D03*
Y13662D03*
Y21654D03*
Y29646D03*
Y37638D03*
Y45630D03*
X1900945Y-6318D03*
Y1674D03*
Y9666D03*
Y17658D03*
Y25650D03*
Y33642D03*
Y41634D03*
Y49626D03*
G54D198*
X1871988Y55350D03*
X1875924D03*
Y47250D03*
X1871988D03*
X1873956Y55350D03*
X1877892D03*
X1873956Y47250D03*
X1877892D03*
G54D189*
X1730814Y565314D03*
X1728254Y575914D03*
X1733369D03*
X1725694D03*
X1730814D03*
X1733369Y565314D03*
X1728254D03*
X1725694D03*
G54D69*
X64500Y359300D03*
X68000D03*
X667500Y257800D03*
X1504631Y605456D03*
X1466610Y607929D03*
G54D87*
X589349Y335730D03*
G54D78*
X346748Y492120D03*
X367615Y491120D03*
X1037657Y487300D03*
G54D96*
X649591Y138067D03*
X652282Y184964D03*
G54D88*
X601049Y345981D03*
G54D97*
X638541Y171945D03*
Y454425D03*
X752641Y159945D03*
Y442425D03*
X1288068Y171945D03*
Y454425D03*
X1402168Y159945D03*
Y442425D03*
X1536123Y23968D03*
X1674921Y528523D03*
Y545059D03*
X1773347Y528523D03*
Y545059D03*
X1872343Y29874D03*
G54D199*
X1854501Y195587D03*
X1859854Y501441D03*
Y525063D03*
X1952756Y589960D03*
X1944882Y582086D03*
X1952756D03*
X1944882Y574212D03*
X1952756D03*
X1944882Y566338D03*
X1952756D03*
X1944882Y558464D03*
Y589960D03*
Y605708D03*
X1952756D03*
X1944882Y597834D03*
X1952756D03*
G54D79*
X388187Y-5822D03*
Y31978D03*
Y13078D03*
Y69778D03*
Y50878D03*
Y88678D03*
Y514079D03*
Y532955D03*
Y570755D03*
Y589679D03*
Y551879D03*
Y608555D03*
X1037797Y-5822D03*
Y31978D03*
Y13078D03*
Y69778D03*
Y88678D03*
Y50878D03*
Y514079D03*
Y570755D03*
Y532955D03*
Y589679D03*
Y551879D03*
Y608555D03*
G54D89*
X594800Y366894D03*
G54D98*
X634264Y197080D03*
G54D99*
X634044Y184570D03*
M02*
